FILE_TYPE=LIBRARY_PARTS;
primitive 'LCMXO2_A','LCMXO2_A_SM';
  pin
    'GND'<7>:
      PIN_NUMBER='(92)';
      PINUSE='GROUND';
      NO_LOAD_CHECK='Both';
      NO_IO_CHECK='Both';
      NO_ASSERT_CHECK='TRUE';
      NO_DIR_CHECK='TRUE';
      ALLOW_CONNECT='TRUE';
    'GND'<6>:
      PIN_NUMBER='(79)';
      PINUSE='GROUND';
      NO_LOAD_CHECK='Both';
      NO_IO_CHECK='Both';
      NO_ASSERT_CHECK='TRUE';
      NO_DIR_CHECK='TRUE';
      ALLOW_CONNECT='TRUE';
    'GND'<5>:
      PIN_NUMBER='(72)';
      PINUSE='GROUND';
      NO_LOAD_CHECK='Both';
      NO_IO_CHECK='Both';
      NO_ASSERT_CHECK='TRUE';
      NO_DIR_CHECK='TRUE';
      ALLOW_CONNECT='TRUE';
    'GND'<4>:
      PIN_NUMBER='(56)';
      PINUSE='GROUND';
      NO_LOAD_CHECK='Both';
      NO_IO_CHECK='Both';
      NO_ASSERT_CHECK='TRUE';
      NO_DIR_CHECK='TRUE';
      ALLOW_CONNECT='TRUE';
    'GND'<3>:
      PIN_NUMBER='(44)';
      PINUSE='GROUND';
      NO_LOAD_CHECK='Both';
      NO_IO_CHECK='Both';
      NO_ASSERT_CHECK='TRUE';
      NO_DIR_CHECK='TRUE';
      ALLOW_CONNECT='TRUE';
    'GND'<2>:
      PIN_NUMBER='(33)';
      PINUSE='GROUND';
      NO_LOAD_CHECK='Both';
      NO_IO_CHECK='Both';
      NO_ASSERT_CHECK='TRUE';
      NO_DIR_CHECK='TRUE';
      ALLOW_CONNECT='TRUE';
    'GND'<1>:
      PIN_NUMBER='(22)';
      PINUSE='GROUND';
      NO_LOAD_CHECK='Both';
      NO_IO_CHECK='Both';
      NO_ASSERT_CHECK='TRUE';
      NO_DIR_CHECK='TRUE';
      ALLOW_CONNECT='TRUE';
    'GND'<0>:
      PIN_NUMBER='(6)';
      PINUSE='GROUND';
      NO_LOAD_CHECK='Both';
      NO_IO_CHECK='Both';
      NO_ASSERT_CHECK='TRUE';
      NO_DIR_CHECK='TRUE';
      ALLOW_CONNECT='TRUE';
    'NC'<2>:
      PIN_NUMBER='(89)';
      PINUSE='NC';
      NO_LOAD_CHECK='Both';
      NO_IO_CHECK='Both';
      NO_ASSERT_CHECK='TRUE';
      NO_DIR_CHECK='TRUE';
      ALLOW_CONNECT='TRUE';
    'NC'<1>:
      PIN_NUMBER='(61)';
      PINUSE='NC';
      NO_LOAD_CHECK='Both';
      NO_IO_CHECK='Both';
      NO_ASSERT_CHECK='TRUE';
      NO_DIR_CHECK='TRUE';
      ALLOW_CONNECT='TRUE';
    'NC'<0>:
      PIN_NUMBER='(11)';
      PINUSE='NC';
      NO_LOAD_CHECK='Both';
      NO_IO_CHECK='Both';
      NO_ASSERT_CHECK='TRUE';
      NO_DIR_CHECK='TRUE';
      ALLOW_CONNECT='TRUE';
    'PB10A':
      PIN_NUMBER='(36)';
      BIDIRECTIONAL='TRUE';
      INPUT_LOAD='(-0.01,0.01)';
      OUTPUT_LOAD='(1.0,-1.0)';
    'PB10B':
      PIN_NUMBER='(37)';
      BIDIRECTIONAL='TRUE';
      INPUT_LOAD='(-0.01,0.01)';
      OUTPUT_LOAD='(1.0,-1.0)';
    'PB10C':
      PIN_NUMBER='(38)';
      BIDIRECTIONAL='TRUE';
      INPUT_LOAD='(-0.01,0.01)';
      OUTPUT_LOAD='(1.0,-1.0)';
    'PB10D':
      PIN_NUMBER='(39)';
      BIDIRECTIONAL='TRUE';
      INPUT_LOAD='(-0.01,0.01)';
      OUTPUT_LOAD='(1.0,-1.0)';
    'PB12A':
      PIN_NUMBER='(40)';
      BIDIRECTIONAL='TRUE';
      INPUT_LOAD='(-0.01,0.01)';
      OUTPUT_LOAD='(1.0,-1.0)';
    'PB12B':
      PIN_NUMBER='(41)';
      BIDIRECTIONAL='TRUE';
      INPUT_LOAD='(-0.01,0.01)';
      OUTPUT_LOAD='(1.0,-1.0)';
    'PB12C':
      PIN_NUMBER='(42)';
      BIDIRECTIONAL='TRUE';
      INPUT_LOAD='(-0.01,0.01)';
      OUTPUT_LOAD='(1.0,-1.0)';
    'PB12D':
      PIN_NUMBER='(43)';
      BIDIRECTIONAL='TRUE';
      INPUT_LOAD='(-0.01,0.01)';
      OUTPUT_LOAD='(1.0,-1.0)';
    'PB14A':
      PIN_NUMBER='(45)';
      BIDIRECTIONAL='TRUE';
      INPUT_LOAD='(-0.01,0.01)';
      OUTPUT_LOAD='(1.0,-1.0)';
    'PB14B':
      PIN_NUMBER='(47)';
      BIDIRECTIONAL='TRUE';
      INPUT_LOAD='(-0.01,0.01)';
      OUTPUT_LOAD='(1.0,-1.0)';
    'PB14C':
      PIN_NUMBER='(48)';
      BIDIRECTIONAL='TRUE';
      INPUT_LOAD='(-0.01,0.01)';
      OUTPUT_LOAD='(1.0,-1.0)';
    'PB14D':
      PIN_NUMBER='(49)';
      BIDIRECTIONAL='TRUE';
      INPUT_LOAD='(-0.01,0.01)';
      OUTPUT_LOAD='(1.0,-1.0)';
    'PB4A':
      PIN_NUMBER='(27)';
      BIDIRECTIONAL='TRUE';
      INPUT_LOAD='(-0.01,0.01)';
      OUTPUT_LOAD='(1.0,-1.0)';
    'PB4B':
      PIN_NUMBER='(28)';
      BIDIRECTIONAL='TRUE';
      INPUT_LOAD='(-0.01,0.01)';
      OUTPUT_LOAD='(1.0,-1.0)';
    'PB4C':
      PIN_NUMBER='(29)';
      BIDIRECTIONAL='TRUE';
      INPUT_LOAD='(-0.01,0.01)';
      OUTPUT_LOAD='(1.0,-1.0)';
    'PB4D':
      PIN_NUMBER='(30)';
      BIDIRECTIONAL='TRUE';
      INPUT_LOAD='(-0.01,0.01)';
      OUTPUT_LOAD='(1.0,-1.0)';
    'PB6A':
      PIN_NUMBER='(31)';
      BIDIRECTIONAL='TRUE';
      INPUT_LOAD='(-0.01,0.01)';
      OUTPUT_LOAD='(1.0,-1.0)';
    'PB6B':
      PIN_NUMBER='(32)';
      BIDIRECTIONAL='TRUE';
      INPUT_LOAD='(-0.01,0.01)';
      OUTPUT_LOAD='(1.0,-1.0)';
    'PB6C':
      PIN_NUMBER='(34)';
      BIDIRECTIONAL='TRUE';
      INPUT_LOAD='(-0.01,0.01)';
      OUTPUT_LOAD='(1.0,-1.0)';
    'PB6D':
      PIN_NUMBER='(35)';
      BIDIRECTIONAL='TRUE';
      INPUT_LOAD='(-0.01,0.01)';
      OUTPUT_LOAD='(1.0,-1.0)';
    'PL2A':
      PIN_NUMBER='(1)';
      BIDIRECTIONAL='TRUE';
      INPUT_LOAD='(-0.01,0.01)';
      OUTPUT_LOAD='(1.0,-1.0)';
    'PL2B':
      PIN_NUMBER='(2)';
      BIDIRECTIONAL='TRUE';
      INPUT_LOAD='(-0.01,0.01)';
      OUTPUT_LOAD='(1.0,-1.0)';
    'PL2C':
      PIN_NUMBER='(3)';
      BIDIRECTIONAL='TRUE';
      INPUT_LOAD='(-0.01,0.01)';
      OUTPUT_LOAD='(1.0,-1.0)';
    'PL2D':
      PIN_NUMBER='(4)';
      BIDIRECTIONAL='TRUE';
      INPUT_LOAD='(-0.01,0.01)';
      OUTPUT_LOAD='(1.0,-1.0)';
    'PL3A':
      PIN_NUMBER='(7)';
      BIDIRECTIONAL='TRUE';
      INPUT_LOAD='(-0.01,0.01)';
      OUTPUT_LOAD='(1.0,-1.0)';
    'PL3B':
      PIN_NUMBER='(8)';
      BIDIRECTIONAL='TRUE';
      INPUT_LOAD='(-0.01,0.01)';
      OUTPUT_LOAD='(1.0,-1.0)';
    'PL3C':
      PIN_NUMBER='(9)';
      BIDIRECTIONAL='TRUE';
      INPUT_LOAD='(-0.01,0.01)';
      OUTPUT_LOAD='(1.0,-1.0)';
    'PL3D':
      PIN_NUMBER='(10)';
      BIDIRECTIONAL='TRUE';
      INPUT_LOAD='(-0.01,0.01)';
      OUTPUT_LOAD='(1.0,-1.0)';
    'PL5A':
      PIN_NUMBER='(12)';
      BIDIRECTIONAL='TRUE';
      INPUT_LOAD='(-0.01,0.01)';
      OUTPUT_LOAD='(1.0,-1.0)';
    'PL5B':
      PIN_NUMBER='(13)';
      BIDIRECTIONAL='TRUE';
      INPUT_LOAD='(-0.01,0.01)';
      OUTPUT_LOAD='(1.0,-1.0)';
    'PL5C':
      PIN_NUMBER='(14)';
      BIDIRECTIONAL='TRUE';
      INPUT_LOAD='(-0.01,0.01)';
      OUTPUT_LOAD='(1.0,-1.0)';
    'PL5D':
      PIN_NUMBER='(15)';
      BIDIRECTIONAL='TRUE';
      INPUT_LOAD='(-0.01,0.01)';
      OUTPUT_LOAD='(1.0,-1.0)';
    'PL6A':
      PIN_NUMBER='(16)';
      BIDIRECTIONAL='TRUE';
      INPUT_LOAD='(-0.01,0.01)';
      OUTPUT_LOAD='(1.0,-1.0)';
    'PL6B':
      PIN_NUMBER='(17)';
      BIDIRECTIONAL='TRUE';
      INPUT_LOAD='(-0.01,0.01)';
      OUTPUT_LOAD='(1.0,-1.0)';
    'PL6C':
      PIN_NUMBER='(18)';
      BIDIRECTIONAL='TRUE';
      INPUT_LOAD='(-0.01,0.01)';
      OUTPUT_LOAD='(1.0,-1.0)';
    'PL6D':
      PIN_NUMBER='(19)';
      BIDIRECTIONAL='TRUE';
      INPUT_LOAD='(-0.01,0.01)';
      OUTPUT_LOAD='(1.0,-1.0)';
    'PL7A':
      PIN_NUMBER='(20)';
      BIDIRECTIONAL='TRUE';
      INPUT_LOAD='(-0.01,0.01)';
      OUTPUT_LOAD='(1.0,-1.0)';
    'PL7B':
      PIN_NUMBER='(21)';
      BIDIRECTIONAL='TRUE';
      INPUT_LOAD='(-0.01,0.01)';
      OUTPUT_LOAD='(1.0,-1.0)';
    'PL7C':
      PIN_NUMBER='(24)';
      BIDIRECTIONAL='TRUE';
      INPUT_LOAD='(-0.01,0.01)';
      OUTPUT_LOAD='(1.0,-1.0)';
    'PL7D':
      PIN_NUMBER='(25)';
      BIDIRECTIONAL='TRUE';
      INPUT_LOAD='(-0.01,0.01)';
      OUTPUT_LOAD='(1.0,-1.0)';
    'PR2A':
      PIN_NUMBER='(75)';
      BIDIRECTIONAL='TRUE';
      INPUT_LOAD='(-0.01,0.01)';
      OUTPUT_LOAD='(1.0,-1.0)';
    'PR2B':
      PIN_NUMBER='(74)';
      BIDIRECTIONAL='TRUE';
      INPUT_LOAD='(-0.01,0.01)';
      OUTPUT_LOAD='(1.0,-1.0)';
    'PR2C':
      PIN_NUMBER='(71)';
      BIDIRECTIONAL='TRUE';
      INPUT_LOAD='(-0.01,0.01)';
      OUTPUT_LOAD='(1.0,-1.0)';
    'PR2D':
      PIN_NUMBER='(70)';
      BIDIRECTIONAL='TRUE';
      INPUT_LOAD='(-0.01,0.01)';
      OUTPUT_LOAD='(1.0,-1.0)';
    'PR3A':
      PIN_NUMBER='(69)';
      BIDIRECTIONAL='TRUE';
      INPUT_LOAD='(-0.01,0.01)';
      OUTPUT_LOAD='(1.0,-1.0)';
    'PR3B':
      PIN_NUMBER='(68)';
      BIDIRECTIONAL='TRUE';
      INPUT_LOAD='(-0.01,0.01)';
      OUTPUT_LOAD='(1.0,-1.0)';
    'PR3C':
      PIN_NUMBER='(67)';
      BIDIRECTIONAL='TRUE';
      INPUT_LOAD='(-0.01,0.01)';
      OUTPUT_LOAD='(1.0,-1.0)';
    'PR3D':
      PIN_NUMBER='(66)';
      BIDIRECTIONAL='TRUE';
      INPUT_LOAD='(-0.01,0.01)';
      OUTPUT_LOAD='(1.0,-1.0)';
    'PR5A':
      PIN_NUMBER='(65)';
      BIDIRECTIONAL='TRUE';
      INPUT_LOAD='(-0.01,0.01)';
      OUTPUT_LOAD='(1.0,-1.0)';
    'PR5B':
      PIN_NUMBER='(64)';
      BIDIRECTIONAL='TRUE';
      INPUT_LOAD='(-0.01,0.01)';
      OUTPUT_LOAD='(1.0,-1.0)';
    'PR5C':
      PIN_NUMBER='(63)';
      BIDIRECTIONAL='TRUE';
      INPUT_LOAD='(-0.01,0.01)';
      OUTPUT_LOAD='(1.0,-1.0)';
    'PR5D':
      PIN_NUMBER='(62)';
      BIDIRECTIONAL='TRUE';
      INPUT_LOAD='(-0.01,0.01)';
      OUTPUT_LOAD='(1.0,-1.0)';
    'PR6A':
      PIN_NUMBER='(60)';
      BIDIRECTIONAL='TRUE';
      INPUT_LOAD='(-0.01,0.01)';
      OUTPUT_LOAD='(1.0,-1.0)';
    'PR6B':
      PIN_NUMBER='(59)';
      BIDIRECTIONAL='TRUE';
      INPUT_LOAD='(-0.01,0.01)';
      OUTPUT_LOAD='(1.0,-1.0)';
    'PR6C':
      PIN_NUMBER='(58)';
      BIDIRECTIONAL='TRUE';
      INPUT_LOAD='(-0.01,0.01)';
      OUTPUT_LOAD='(1.0,-1.0)';
    'PR6D':
      PIN_NUMBER='(57)';
      BIDIRECTIONAL='TRUE';
      INPUT_LOAD='(-0.01,0.01)';
      OUTPUT_LOAD='(1.0,-1.0)';
    'PR7A':
      PIN_NUMBER='(54)';
      BIDIRECTIONAL='TRUE';
      INPUT_LOAD='(-0.01,0.01)';
      OUTPUT_LOAD='(1.0,-1.0)';
    'PR7B':
      PIN_NUMBER='(53)';
      BIDIRECTIONAL='TRUE';
      INPUT_LOAD='(-0.01,0.01)';
      OUTPUT_LOAD='(1.0,-1.0)';
    'PR7C':
      PIN_NUMBER='(52)';
      BIDIRECTIONAL='TRUE';
      INPUT_LOAD='(-0.01,0.01)';
      OUTPUT_LOAD='(1.0,-1.0)';
    'PR7D':
      PIN_NUMBER='(51)';
      BIDIRECTIONAL='TRUE';
      INPUT_LOAD='(-0.01,0.01)';
      OUTPUT_LOAD='(1.0,-1.0)';
    'PT10A':
      PIN_NUMBER='(84)';
      BIDIRECTIONAL='TRUE';
      INPUT_LOAD='(-0.01,0.01)';
      OUTPUT_LOAD='(1.0,-1.0)';
    'PT10B':
      PIN_NUMBER='(83)';
      BIDIRECTIONAL='TRUE';
      INPUT_LOAD='(-0.01,0.01)';
      OUTPUT_LOAD='(1.0,-1.0)';
    'PT10C':
      PIN_NUMBER='(82)';
      BIDIRECTIONAL='TRUE';
      INPUT_LOAD='(-0.01,0.01)';
      OUTPUT_LOAD='(1.0,-1.0)';
    'PT10D':
      PIN_NUMBER='(81)';
      BIDIRECTIONAL='TRUE';
      INPUT_LOAD='(-0.01,0.01)';
      OUTPUT_LOAD='(1.0,-1.0)';
    'PT11A':
      PIN_NUMBER='(78)';
      BIDIRECTIONAL='TRUE';
      INPUT_LOAD='(-0.01,0.01)';
      OUTPUT_LOAD='(1.0,-1.0)';
    'PT11C':
      PIN_NUMBER='(77)';
      BIDIRECTIONAL='TRUE';
      INPUT_LOAD='(-0.01,0.01)';
      OUTPUT_LOAD='(1.0,-1.0)';
    'PT11D':
      PIN_NUMBER='(76)';
      BIDIRECTIONAL='TRUE';
      INPUT_LOAD='(-0.01,0.01)';
      OUTPUT_LOAD='(1.0,-1.0)';
    'PT6A':
      PIN_NUMBER='(99)';
      BIDIRECTIONAL='TRUE';
      INPUT_LOAD='(-0.01,0.01)';
      OUTPUT_LOAD='(1.0,-1.0)';
    'PT6B':
      PIN_NUMBER='(98)';
      BIDIRECTIONAL='TRUE';
      INPUT_LOAD='(-0.01,0.01)';
      OUTPUT_LOAD='(1.0,-1.0)';
    'PT6C':
      PIN_NUMBER='(97)';
      BIDIRECTIONAL='TRUE';
      INPUT_LOAD='(-0.01,0.01)';
      OUTPUT_LOAD='(1.0,-1.0)';
    'PT6D':
      PIN_NUMBER='(96)';
      BIDIRECTIONAL='TRUE';
      INPUT_LOAD='(-0.01,0.01)';
      OUTPUT_LOAD='(1.0,-1.0)';
    'PT7A':
      PIN_NUMBER='(95)';
      BIDIRECTIONAL='TRUE';
      INPUT_LOAD='(-0.01,0.01)';
      OUTPUT_LOAD='(1.0,-1.0)';
    'PT7B':
      PIN_NUMBER='(94)';
      BIDIRECTIONAL='TRUE';
      INPUT_LOAD='(-0.01,0.01)';
      OUTPUT_LOAD='(1.0,-1.0)';
    'PT7C':
      PIN_NUMBER='(91)';
      BIDIRECTIONAL='TRUE';
      INPUT_LOAD='(-0.01,0.01)';
      OUTPUT_LOAD='(1.0,-1.0)';
    'PT7D':
      PIN_NUMBER='(90)';
      BIDIRECTIONAL='TRUE';
      INPUT_LOAD='(-0.01,0.01)';
      OUTPUT_LOAD='(1.0,-1.0)';
    'PT9A':
      PIN_NUMBER='(88)';
      BIDIRECTIONAL='TRUE';
      INPUT_LOAD='(-0.01,0.01)';
      OUTPUT_LOAD='(1.0,-1.0)';
    'PT9B':
      PIN_NUMBER='(87)';
      BIDIRECTIONAL='TRUE';
      INPUT_LOAD='(-0.01,0.01)';
      OUTPUT_LOAD='(1.0,-1.0)';
    'PT9C':
      PIN_NUMBER='(86)';
      BIDIRECTIONAL='TRUE';
      INPUT_LOAD='(-0.01,0.01)';
      OUTPUT_LOAD='(1.0,-1.0)';
    'PT9D':
      PIN_NUMBER='(85)';
      BIDIRECTIONAL='TRUE';
      INPUT_LOAD='(-0.01,0.01)';
      OUTPUT_LOAD='(1.0,-1.0)';
    'VCC'<1>:
      PIN_NUMBER='(100)';
      PINUSE='POWER';
      NO_LOAD_CHECK='Both';
      NO_IO_CHECK='Both';
      NO_ASSERT_CHECK='TRUE';
      NO_DIR_CHECK='TRUE';
      ALLOW_CONNECT='TRUE';
    'VCC'<0>:
      PIN_NUMBER='(50)';
      PINUSE='POWER';
      NO_LOAD_CHECK='Both';
      NO_IO_CHECK='Both';
      NO_ASSERT_CHECK='TRUE';
      NO_DIR_CHECK='TRUE';
      ALLOW_CONNECT='TRUE';
    'VCCIO0'<1>:
      PIN_NUMBER='(93)';
      PINUSE='POWER';
      NO_LOAD_CHECK='Both';
      NO_IO_CHECK='Both';
      NO_ASSERT_CHECK='TRUE';
      NO_DIR_CHECK='TRUE';
      ALLOW_CONNECT='TRUE';
    'VCCIO0'<0>:
      PIN_NUMBER='(80)';
      PINUSE='POWER';
      NO_LOAD_CHECK='Both';
      NO_IO_CHECK='Both';
      NO_ASSERT_CHECK='TRUE';
      NO_DIR_CHECK='TRUE';
      ALLOW_CONNECT='TRUE';
    'VCCIO1'<1>:
      PIN_NUMBER='(73)';
      PINUSE='POWER';
      NO_LOAD_CHECK='Both';
      NO_IO_CHECK='Both';
      NO_ASSERT_CHECK='TRUE';
      NO_DIR_CHECK='TRUE';
      ALLOW_CONNECT='TRUE';
    'VCCIO1'<0>:
      PIN_NUMBER='(55)';
      PINUSE='POWER';
      NO_LOAD_CHECK='Both';
      NO_IO_CHECK='Both';
      NO_ASSERT_CHECK='TRUE';
      NO_DIR_CHECK='TRUE';
      ALLOW_CONNECT='TRUE';
    'VCCIO2'<1>:
      PIN_NUMBER='(46)';
      PINUSE='POWER';
      NO_LOAD_CHECK='Both';
      NO_IO_CHECK='Both';
      NO_ASSERT_CHECK='TRUE';
      NO_DIR_CHECK='TRUE';
      ALLOW_CONNECT='TRUE';
    'VCCIO2'<0>:
      PIN_NUMBER='(26)';
      PINUSE='POWER';
      NO_LOAD_CHECK='Both';
      NO_IO_CHECK='Both';
      NO_ASSERT_CHECK='TRUE';
      NO_DIR_CHECK='TRUE';
      ALLOW_CONNECT='TRUE';
    'VCCIO3'<1>:
      PIN_NUMBER='(23)';
      PINUSE='POWER';
      NO_LOAD_CHECK='Both';
      NO_IO_CHECK='Both';
      NO_ASSERT_CHECK='TRUE';
      NO_DIR_CHECK='TRUE';
      ALLOW_CONNECT='TRUE';
    'VCCIO3'<0>:
      PIN_NUMBER='(5)';
      PINUSE='POWER';
      NO_LOAD_CHECK='Both';
      NO_IO_CHECK='Both';
      NO_ASSERT_CHECK='TRUE';
      NO_DIR_CHECK='TRUE';
      ALLOW_CONNECT='TRUE';
  end_pin;
  body
    PART_NAME='LCMXO2_A';
    PHYS_DES_PREFIX='U';
  end_body;
end_primitive;

primitive 'LCMXO2_A_BGA';
  pin
    'GND'<9>:
      PIN_NUMBER='(0,P10)';
      PINUSE='GROUND';
      NO_LOAD_CHECK='Both';
      NO_IO_CHECK='Both';
      NO_ASSERT_CHECK='TRUE';
      NO_DIR_CHECK='TRUE';
      ALLOW_CONNECT='TRUE';
    'GND'<8>:
      PIN_NUMBER='(0,P5)';
      PINUSE='GROUND';
      NO_LOAD_CHECK='Both';
      NO_IO_CHECK='Both';
      NO_ASSERT_CHECK='TRUE';
      NO_DIR_CHECK='TRUE';
      ALLOW_CONNECT='TRUE';
    'GND'<7>:
      PIN_NUMBER='(0,L13)';
      PINUSE='GROUND';
      NO_LOAD_CHECK='Both';
      NO_IO_CHECK='Both';
      NO_ASSERT_CHECK='TRUE';
      NO_DIR_CHECK='TRUE';
      ALLOW_CONNECT='TRUE';
    'GND'<6>:
      PIN_NUMBER='(0,L2)';
      PINUSE='GROUND';
      NO_LOAD_CHECK='Both';
      NO_IO_CHECK='Both';
      NO_ASSERT_CHECK='TRUE';
      NO_DIR_CHECK='TRUE';
      ALLOW_CONNECT='TRUE';
    'GND'<5>:
      PIN_NUMBER='(0,H13)';
      PINUSE='GROUND';
      NO_LOAD_CHECK='Both';
      NO_IO_CHECK='Both';
      NO_ASSERT_CHECK='TRUE';
      NO_DIR_CHECK='TRUE';
      ALLOW_CONNECT='TRUE';
    'GND'<4>:
      PIN_NUMBER='(0,G2)';
      PINUSE='GROUND';
      NO_LOAD_CHECK='Both';
      NO_IO_CHECK='Both';
      NO_ASSERT_CHECK='TRUE';
      NO_DIR_CHECK='TRUE';
      ALLOW_CONNECT='TRUE';
    'GND'<3>:
      PIN_NUMBER='(0,D13)';
      PINUSE='GROUND';
      NO_LOAD_CHECK='Both';
      NO_IO_CHECK='Both';
      NO_ASSERT_CHECK='TRUE';
      NO_DIR_CHECK='TRUE';
      ALLOW_CONNECT='TRUE';
    'GND'<2>:
      PIN_NUMBER='(0,D2)';
      PINUSE='GROUND';
      NO_LOAD_CHECK='Both';
      NO_IO_CHECK='Both';
      NO_ASSERT_CHECK='TRUE';
      NO_DIR_CHECK='TRUE';
      ALLOW_CONNECT='TRUE';
    'GND'<1>:
      PIN_NUMBER='(0,B11)';
      PINUSE='GROUND';
      NO_LOAD_CHECK='Both';
      NO_IO_CHECK='Both';
      NO_ASSERT_CHECK='TRUE';
      NO_DIR_CHECK='TRUE';
      ALLOW_CONNECT='TRUE';
    'GND'<0>:
      PIN_NUMBER='(0,A5)';
      PINUSE='GROUND';
      NO_LOAD_CHECK='Both';
      NO_IO_CHECK='Both';
      NO_ASSERT_CHECK='TRUE';
      NO_DIR_CHECK='TRUE';
      ALLOW_CONNECT='TRUE';
    'NC'<0>:
      PIN_NUMBER='(0,C7)';
      PINUSE='NC';
      NO_LOAD_CHECK='Both';
      NO_IO_CHECK='Both';
      NO_ASSERT_CHECK='TRUE';
      NO_DIR_CHECK='TRUE';
      ALLOW_CONNECT='TRUE';
    'PB11A_PCLKP2_1':
      PIN_NUMBER='(M7,0)';
      BIDIRECTIONAL='TRUE';
      INPUT_LOAD='(-0.01,0.01)';
      OUTPUT_LOAD='(1.0,-1.0)';
    'PB11B_PCLKN2_1':
      PIN_NUMBER='(N8,0)';
      BIDIRECTIONAL='TRUE';
      INPUT_LOAD='(-0.01,0.01)';
      OUTPUT_LOAD='(1.0,-1.0)';
    'PB11C':
      PIN_NUMBER='(P7,0)';
      BIDIRECTIONAL='TRUE';
      INPUT_LOAD='(-0.01,0.01)';
      OUTPUT_LOAD='(1.0,-1.0)';
    'PB11D':
      PIN_NUMBER='(N7,0)';
      BIDIRECTIONAL='TRUE';
      INPUT_LOAD='(-0.01,0.01)';
      OUTPUT_LOAD='(1.0,-1.0)';
    'PB15A':
      PIN_NUMBER='(P8,0)';
      BIDIRECTIONAL='TRUE';
      INPUT_LOAD='(-0.01,0.01)';
      OUTPUT_LOAD='(1.0,-1.0)';
    'PB15B':
      PIN_NUMBER='(M8,0)';
      BIDIRECTIONAL='TRUE';
      INPUT_LOAD='(-0.01,0.01)';
      OUTPUT_LOAD='(1.0,-1.0)';
    'PB15C':
      PIN_NUMBER='(P9,0)';
      BIDIRECTIONAL='TRUE';
      INPUT_LOAD='(-0.01,0.01)';
      OUTPUT_LOAD='(1.0,-1.0)';
    'PB15D':
      PIN_NUMBER='(N9,0)';
      BIDIRECTIONAL='TRUE';
      INPUT_LOAD='(-0.01,0.01)';
      OUTPUT_LOAD='(1.0,-1.0)';
    'PB18A':
      PIN_NUMBER='(M9,0)';
      BIDIRECTIONAL='TRUE';
      INPUT_LOAD='(-0.01,0.01)';
      OUTPUT_LOAD='(1.0,-1.0)';
    'PB18B':
      PIN_NUMBER='(N10,0)';
      BIDIRECTIONAL='TRUE';
      INPUT_LOAD='(-0.01,0.01)';
      OUTPUT_LOAD='(1.0,-1.0)';
    'PB18C':
      PIN_NUMBER='(M10,0)';
      BIDIRECTIONAL='TRUE';
      INPUT_LOAD='(-0.01,0.01)';
      OUTPUT_LOAD='(1.0,-1.0)';
    'PB18D':
      PIN_NUMBER='(P11,0)';
      BIDIRECTIONAL='TRUE';
      INPUT_LOAD='(-0.01,0.01)';
      OUTPUT_LOAD='(1.0,-1.0)';
    'PB20A':
      PIN_NUMBER='(M11,0)';
      BIDIRECTIONAL='TRUE';
      INPUT_LOAD='(-0.01,0.01)';
      OUTPUT_LOAD='(1.0,-1.0)';
    'PB20B':
      PIN_NUMBER='(P12,0)';
      BIDIRECTIONAL='TRUE';
      INPUT_LOAD='(-0.01,0.01)';
      OUTPUT_LOAD='(1.0,-1.0)';
    'PB20C_SN':
      PIN_NUMBER='(N12,0)';
      BIDIRECTIONAL='TRUE';
      INPUT_LOAD='(-0.01,0.01)';
      OUTPUT_LOAD='(1.0,-1.0)';
    'PB20D_SI_SISPI':
      PIN_NUMBER='(P13,0)';
      BIDIRECTIONAL='TRUE';
      INPUT_LOAD='(-0.01,0.01)';
      OUTPUT_LOAD='(1.0,-1.0)';
    'PB4A':
      PIN_NUMBER='(P2,0)';
      BIDIRECTIONAL='TRUE';
      INPUT_LOAD='(-0.01,0.01)';
      OUTPUT_LOAD='(1.0,-1.0)';
    'PB4B':
      PIN_NUMBER='(N2,0)';
      BIDIRECTIONAL='TRUE';
      INPUT_LOAD='(-0.01,0.01)';
      OUTPUT_LOAD='(1.0,-1.0)';
    'PB4C_CSSPIN':
      PIN_NUMBER='(P3,0)';
      BIDIRECTIONAL='TRUE';
      INPUT_LOAD='(-0.01,0.01)';
      OUTPUT_LOAD='(1.0,-1.0)';
    'PB4D':
      PIN_NUMBER='(M3,0)';
      BIDIRECTIONAL='TRUE';
      INPUT_LOAD='(-0.01,0.01)';
      OUTPUT_LOAD='(1.0,-1.0)';
    'PB6A':
      PIN_NUMBER='(N3,0)';
      BIDIRECTIONAL='TRUE';
      INPUT_LOAD='(-0.01,0.01)';
      OUTPUT_LOAD='(1.0,-1.0)';
    'PB6B':
      PIN_NUMBER='(P4,0)';
      BIDIRECTIONAL='TRUE';
      INPUT_LOAD='(-0.01,0.01)';
      OUTPUT_LOAD='(1.0,-1.0)';
    'PB6C_MCLK_CCLK':
      PIN_NUMBER='(M4,0)';
      BIDIRECTIONAL='TRUE';
      INPUT_LOAD='(-0.01,0.01)';
      OUTPUT_LOAD='(1.0,-1.0)';
    'PB6D_SO_SPISO':
      PIN_NUMBER='(N4,0)';
      BIDIRECTIONAL='TRUE';
      INPUT_LOAD='(-0.01,0.01)';
      OUTPUT_LOAD='(1.0,-1.0)';
    'PB9A_PCLKP2_0':
      PIN_NUMBER='(N6,0)';
      BIDIRECTIONAL='TRUE';
      INPUT_LOAD='(-0.01,0.01)';
      OUTPUT_LOAD='(1.0,-1.0)';
    'PB9B_PCLKN2_0':
      PIN_NUMBER='(P6,0)';
      BIDIRECTIONAL='TRUE';
      INPUT_LOAD='(-0.01,0.01)';
      OUTPUT_LOAD='(1.0,-1.0)';
    'PB9C':
      PIN_NUMBER='(N5,0)';
      BIDIRECTIONAL='TRUE';
      INPUT_LOAD='(-0.01,0.01)';
      OUTPUT_LOAD='(1.0,-1.0)';
    'PB9D':
      PIN_NUMBER='(M5,0)';
      BIDIRECTIONAL='TRUE';
      INPUT_LOAD='(-0.01,0.01)';
      OUTPUT_LOAD='(1.0,-1.0)';
    'PL10B':
      PIN_NUMBER='(L3,0)';
      BIDIRECTIONAL='TRUE';
      INPUT_LOAD='(-0.01,0.01)';
      OUTPUT_LOAD='(1.0,-1.0)';
    'PL10C':
      PIN_NUMBER='(M1,0)';
      BIDIRECTIONAL='TRUE';
      INPUT_LOAD='(-0.01,0.01)';
      OUTPUT_LOAD='(1.0,-1.0)';
    'PL10D':
      PIN_NUMBER='(M2,0)';
      BIDIRECTIONAL='TRUE';
      INPUT_LOAD='(-0.01,0.01)';
      OUTPUT_LOAD='(1.0,-1.0)';
    'PL2A_L_GPLLP_FB':
      PIN_NUMBER='(B1,0)';
      BIDIRECTIONAL='TRUE';
      INPUT_LOAD='(-0.01,0.01)';
      OUTPUT_LOAD='(1.0,-1.0)';
    'PL2B_L_GPLLN_FB':
      PIN_NUMBER='(B2,0)';
      BIDIRECTIONAL='TRUE';
      INPUT_LOAD='(-0.01,0.01)';
      OUTPUT_LOAD='(1.0,-1.0)';
    'PL2C_L_GPLLP_IN':
      PIN_NUMBER='(C1,0)';
      BIDIRECTIONAL='TRUE';
      INPUT_LOAD='(-0.01,0.01)';
      OUTPUT_LOAD='(1.0,-1.0)';
    'PL2D_L_GPLLN_IN':
      PIN_NUMBER='(C3,0)';
      BIDIRECTIONAL='TRUE';
      INPUT_LOAD='(-0.01,0.01)';
      OUTPUT_LOAD='(1.0,-1.0)';
    'PL3A_PCLKP3_2':
      PIN_NUMBER='(C2,0)';
      BIDIRECTIONAL='TRUE';
      INPUT_LOAD='(-0.01,0.01)';
      OUTPUT_LOAD='(1.0,-1.0)';
    'PL3B_PCLKN3_2':
      PIN_NUMBER='(D1,0)';
      BIDIRECTIONAL='TRUE';
      INPUT_LOAD='(-0.01,0.01)';
      OUTPUT_LOAD='(1.0,-1.0)';
    'PL3C':
      PIN_NUMBER='(E1,0)';
      BIDIRECTIONAL='TRUE';
      INPUT_LOAD='(-0.01,0.01)';
      OUTPUT_LOAD='(1.0,-1.0)';
    'PL3D':
      PIN_NUMBER='(E2,0)';
      BIDIRECTIONAL='TRUE';
      INPUT_LOAD='(-0.01,0.01)';
      OUTPUT_LOAD='(1.0,-1.0)';
    'PL4A':
      PIN_NUMBER='(E3,0)';
      BIDIRECTIONAL='TRUE';
      INPUT_LOAD='(-0.01,0.01)';
      OUTPUT_LOAD='(1.0,-1.0)';
    'PL4B':
      PIN_NUMBER='(F2,0)';
      BIDIRECTIONAL='TRUE';
      INPUT_LOAD='(-0.01,0.01)';
      OUTPUT_LOAD='(1.0,-1.0)';
    'PL4C':
      PIN_NUMBER='(F1,0)';
      BIDIRECTIONAL='TRUE';
      INPUT_LOAD='(-0.01,0.01)';
      OUTPUT_LOAD='(1.0,-1.0)';
    'PL4D':
      PIN_NUMBER='(F3,0)';
      BIDIRECTIONAL='TRUE';
      INPUT_LOAD='(-0.01,0.01)';
      OUTPUT_LOAD='(1.0,-1.0)';
    'PL5A_PCLKP3_1':
      PIN_NUMBER='(G3,0)';
      BIDIRECTIONAL='TRUE';
      INPUT_LOAD='(-0.01,0.01)';
      OUTPUT_LOAD='(1.0,-1.0)';
    'PL5B_PCLKN3_1':
      PIN_NUMBER='(H2,0)';
      BIDIRECTIONAL='TRUE';
      INPUT_LOAD='(-0.01,0.01)';
      OUTPUT_LOAD='(1.0,-1.0)';
    'PL5C':
      PIN_NUMBER='(H1,0)';
      BIDIRECTIONAL='TRUE';
      INPUT_LOAD='(-0.01,0.01)';
      OUTPUT_LOAD='(1.0,-1.0)';
    'PL5D':
      PIN_NUMBER='(H3,0)';
      BIDIRECTIONAL='TRUE';
      INPUT_LOAD='(-0.01,0.01)';
      OUTPUT_LOAD='(1.0,-1.0)';
    'PL8A':
      PIN_NUMBER='(J1,0)';
      BIDIRECTIONAL='TRUE';
      INPUT_LOAD='(-0.01,0.01)';
      OUTPUT_LOAD='(1.0,-1.0)';
    'PL8B':
      PIN_NUMBER='(J2,0)';
      BIDIRECTIONAL='TRUE';
      INPUT_LOAD='(-0.01,0.01)';
      OUTPUT_LOAD='(1.0,-1.0)';
    'PL8C':
      PIN_NUMBER='(J3,0)';
      BIDIRECTIONAL='TRUE';
      INPUT_LOAD='(-0.01,0.01)';
      OUTPUT_LOAD='(1.0,-1.0)';
    'PL8D':
      PIN_NUMBER='(K2,0)';
      BIDIRECTIONAL='TRUE';
      INPUT_LOAD='(-0.01,0.01)';
      OUTPUT_LOAD='(1.0,-1.0)';
    'PL9A_PCLKP3_0':
      PIN_NUMBER='(K1,0)';
      BIDIRECTIONAL='TRUE';
      INPUT_LOAD='(-0.01,0.01)';
      OUTPUT_LOAD='(1.0,-1.0)';
    'PL9B_PCLKN3_0':
      PIN_NUMBER='(K3,0)';
      BIDIRECTIONAL='TRUE';
      INPUT_LOAD='(-0.01,0.01)';
      OUTPUT_LOAD='(1.0,-1.0)';
    'PR10A':
      PIN_NUMBER='(M12,0)';
      BIDIRECTIONAL='TRUE';
      INPUT_LOAD='(-0.01,0.01)';
      OUTPUT_LOAD='(1.0,-1.0)';
    'PR10B':
      PIN_NUMBER='(M14,0)';
      BIDIRECTIONAL='TRUE';
      INPUT_LOAD='(-0.01,0.01)';
      OUTPUT_LOAD='(1.0,-1.0)';
    'PR10C':
      PIN_NUMBER='(N13,0)';
      BIDIRECTIONAL='TRUE';
      INPUT_LOAD='(-0.01,0.01)';
      OUTPUT_LOAD='(1.0,-1.0)';
    'PR10D':
      PIN_NUMBER='(N14,0)';
      BIDIRECTIONAL='TRUE';
      INPUT_LOAD='(-0.01,0.01)';
      OUTPUT_LOAD='(1.0,-1.0)';
    'PR2A':
      PIN_NUMBER='(B14,0)';
      BIDIRECTIONAL='TRUE';
      INPUT_LOAD='(-0.01,0.01)';
      OUTPUT_LOAD='(1.0,-1.0)';
    'PR2B':
      PIN_NUMBER='(C13,0)';
      BIDIRECTIONAL='TRUE';
      INPUT_LOAD='(-0.01,0.01)';
      OUTPUT_LOAD='(1.0,-1.0)';
    'PR2C':
      PIN_NUMBER='(C14,0)';
      BIDIRECTIONAL='TRUE';
      INPUT_LOAD='(-0.01,0.01)';
      OUTPUT_LOAD='(1.0,-1.0)';
    'PR2D':
      PIN_NUMBER='(D12,0)';
      BIDIRECTIONAL='TRUE';
      INPUT_LOAD='(-0.01,0.01)';
      OUTPUT_LOAD='(1.0,-1.0)';
    'PR3A':
      PIN_NUMBER='(E12,0)';
      BIDIRECTIONAL='TRUE';
      INPUT_LOAD='(-0.01,0.01)';
      OUTPUT_LOAD='(1.0,-1.0)';
    'PR3B':
      PIN_NUMBER='(E14,0)';
      BIDIRECTIONAL='TRUE';
      INPUT_LOAD='(-0.01,0.01)';
      OUTPUT_LOAD='(1.0,-1.0)';
    'PR4A':
      PIN_NUMBER='(E13,0)';
      BIDIRECTIONAL='TRUE';
      INPUT_LOAD='(-0.01,0.01)';
      OUTPUT_LOAD='(1.0,-1.0)';
    'PR4B':
      PIN_NUMBER='(F12,0)';
      BIDIRECTIONAL='TRUE';
      INPUT_LOAD='(-0.01,0.01)';
      OUTPUT_LOAD='(1.0,-1.0)';
    'PR4C':
      PIN_NUMBER='(F13,0)';
      BIDIRECTIONAL='TRUE';
      INPUT_LOAD='(-0.01,0.01)';
      OUTPUT_LOAD='(1.0,-1.0)';
    'PR4D':
      PIN_NUMBER='(F14,0)';
      BIDIRECTIONAL='TRUE';
      INPUT_LOAD='(-0.01,0.01)';
      OUTPUT_LOAD='(1.0,-1.0)';
    'PR5A':
      PIN_NUMBER='(G12,0)';
      BIDIRECTIONAL='TRUE';
      INPUT_LOAD='(-0.01,0.01)';
      OUTPUT_LOAD='(1.0,-1.0)';
    'PR5B':
      PIN_NUMBER='(G14,0)';
      BIDIRECTIONAL='TRUE';
      INPUT_LOAD='(-0.01,0.01)';
      OUTPUT_LOAD='(1.0,-1.0)';
    'PR5C_PCLKP1_0':
      PIN_NUMBER='(G13,0)';
      BIDIRECTIONAL='TRUE';
      INPUT_LOAD='(-0.01,0.01)';
      OUTPUT_LOAD='(1.0,-1.0)';
    'PR5D_PCLKN1_0':
      PIN_NUMBER='(H12,0)';
      BIDIRECTIONAL='TRUE';
      INPUT_LOAD='(-0.01,0.01)';
      OUTPUT_LOAD='(1.0,-1.0)';
    'PR8A':
      PIN_NUMBER='(J12,0)';
      BIDIRECTIONAL='TRUE';
      INPUT_LOAD='(-0.01,0.01)';
      OUTPUT_LOAD='(1.0,-1.0)';
    'PR8B':
      PIN_NUMBER='(J14,0)';
      BIDIRECTIONAL='TRUE';
      INPUT_LOAD='(-0.01,0.01)';
      OUTPUT_LOAD='(1.0,-1.0)';
    'PR8C':
      PIN_NUMBER='(J13,0)';
      BIDIRECTIONAL='TRUE';
      INPUT_LOAD='(-0.01,0.01)';
      OUTPUT_LOAD='(1.0,-1.0)';
    'PR8D':
      PIN_NUMBER='(K12,0)';
      BIDIRECTIONAL='TRUE';
      INPUT_LOAD='(-0.01,0.01)';
      OUTPUT_LOAD='(1.0,-1.0)';
    'PR9A':
      PIN_NUMBER='(K13,0)';
      BIDIRECTIONAL='TRUE';
      INPUT_LOAD='(-0.01,0.01)';
      OUTPUT_LOAD='(1.0,-1.0)';
    'PR9B':
      PIN_NUMBER='(K14,0)';
      BIDIRECTIONAL='TRUE';
      INPUT_LOAD='(-0.01,0.01)';
      OUTPUT_LOAD='(1.0,-1.0)';
    'PR9C':
      PIN_NUMBER='(L14,0)';
      BIDIRECTIONAL='TRUE';
      INPUT_LOAD='(-0.01,0.01)';
      OUTPUT_LOAD='(1.0,-1.0)';
    'PR9D':
      PIN_NUMBER='(M13,0)';
      BIDIRECTIONAL='TRUE';
      INPUT_LOAD='(-0.01,0.01)';
      OUTPUT_LOAD='(1.0,-1.0)';
    'PT10A':
      PIN_NUMBER='(A3,0)';
      BIDIRECTIONAL='TRUE';
      INPUT_LOAD='(-0.01,0.01)';
      OUTPUT_LOAD='(1.0,-1.0)';
    'PT10B':
      PIN_NUMBER='(C4,0)';
      BIDIRECTIONAL='TRUE';
      INPUT_LOAD='(-0.01,0.01)';
      OUTPUT_LOAD='(1.0,-1.0)';
    'PT10C_TDO':
      PIN_NUMBER='(A4,0)';
      BIDIRECTIONAL='TRUE';
      INPUT_LOAD='(-0.01,0.01)';
      OUTPUT_LOAD='(1.0,-1.0)';
    'PT10D_TDI':
      PIN_NUMBER='(B4,0)';
      BIDIRECTIONAL='TRUE';
      INPUT_LOAD='(-0.01,0.01)';
      OUTPUT_LOAD='(1.0,-1.0)';
    'PT11A':
      PIN_NUMBER='(B5,0)';
      BIDIRECTIONAL='TRUE';
      INPUT_LOAD='(-0.01,0.01)';
      OUTPUT_LOAD='(1.0,-1.0)';
    'PT11B':
      PIN_NUMBER='(C6,0)';
      BIDIRECTIONAL='TRUE';
      INPUT_LOAD='(-0.01,0.01)';
      OUTPUT_LOAD='(1.0,-1.0)';
    'PT11C_TCK':
      PIN_NUMBER='(B6,0)';
      BIDIRECTIONAL='TRUE';
      INPUT_LOAD='(-0.01,0.01)';
      OUTPUT_LOAD='(1.0,-1.0)';
    'PT11D_TMS':
      PIN_NUMBER='(A6,0)';
      BIDIRECTIONAL='TRUE';
      INPUT_LOAD='(-0.01,0.01)';
      OUTPUT_LOAD='(1.0,-1.0)';
    'PT12A_PCLKP0_1':
      PIN_NUMBER='(A7,0)';
      BIDIRECTIONAL='TRUE';
      INPUT_LOAD='(-0.01,0.01)';
      OUTPUT_LOAD='(1.0,-1.0)';
    'PT12B_PCLKN0_1':
      PIN_NUMBER='(B7,0)';
      BIDIRECTIONAL='TRUE';
      INPUT_LOAD='(-0.01,0.01)';
      OUTPUT_LOAD='(1.0,-1.0)';
    'PT12C_SCL_PCLKP0_0':
      PIN_NUMBER='(C8,0)';
      BIDIRECTIONAL='TRUE';
      INPUT_LOAD='(-0.01,0.01)';
      OUTPUT_LOAD='(1.0,-1.0)';
    'PT12D_SDA_PCLKN0_0':
      PIN_NUMBER='(B8,0)';
      BIDIRECTIONAL='TRUE';
      INPUT_LOAD='(-0.01,0.01)';
      OUTPUT_LOAD='(1.0,-1.0)';
    'PT15A':
      PIN_NUMBER='(C9,0)';
      BIDIRECTIONAL='TRUE';
      INPUT_LOAD='(-0.01,0.01)';
      OUTPUT_LOAD='(1.0,-1.0)';
    'PT15B':
      PIN_NUMBER='(A9,0)';
      BIDIRECTIONAL='TRUE';
      INPUT_LOAD='(-0.01,0.01)';
      OUTPUT_LOAD='(1.0,-1.0)';
    'PT15C_JTAGENB':
      PIN_NUMBER='(B9,0)';
      BIDIRECTIONAL='TRUE';
      INPUT_LOAD='(-0.01,0.01)';
      OUTPUT_LOAD='(1.0,-1.0)';
    'PT15D_PROGRAMN':
      PIN_NUMBER='(C10,0)';
      BIDIRECTIONAL='TRUE';
      INPUT_LOAD='(-0.01,0.01)';
      OUTPUT_LOAD='(1.0,-1.0)';
    'PT16A':
      PIN_NUMBER='(A10,0)';
      BIDIRECTIONAL='TRUE';
      INPUT_LOAD='(-0.01,0.01)';
      OUTPUT_LOAD='(1.0,-1.0)';
    'PT16B':
      PIN_NUMBER='(C11,0)';
      BIDIRECTIONAL='TRUE';
      INPUT_LOAD='(-0.01,0.01)';
      OUTPUT_LOAD='(1.0,-1.0)';
    'PT16C':
      PIN_NUMBER='(A11,0)';
      BIDIRECTIONAL='TRUE';
      INPUT_LOAD='(-0.01,0.01)';
      OUTPUT_LOAD='(1.0,-1.0)';
    'PT16D':
      PIN_NUMBER='(B12,0)';
      BIDIRECTIONAL='TRUE';
      INPUT_LOAD='(-0.01,0.01)';
      OUTPUT_LOAD='(1.0,-1.0)';
    'PT17A':
      PIN_NUMBER='(C12,0)';
      BIDIRECTIONAL='TRUE';
      INPUT_LOAD='(-0.01,0.01)';
      OUTPUT_LOAD='(1.0,-1.0)';
    'PT17B':
      PIN_NUMBER='(A12,0)';
      BIDIRECTIONAL='TRUE';
      INPUT_LOAD='(-0.01,0.01)';
      OUTPUT_LOAD='(1.0,-1.0)';
    'PT17C_INITN':
      PIN_NUMBER='(B13,0)';
      BIDIRECTIONAL='TRUE';
      INPUT_LOAD='(-0.01,0.01)';
      OUTPUT_LOAD='(1.0,-1.0)';
    'PT17D_DONE':
      PIN_NUMBER='(A13,0)';
      BIDIRECTIONAL='TRUE';
      INPUT_LOAD='(-0.01,0.01)';
      OUTPUT_LOAD='(1.0,-1.0)';
    'PT9A':
      PIN_NUMBER='(A2,0)';
      BIDIRECTIONAL='TRUE';
      INPUT_LOAD='(-0.01,0.01)';
      OUTPUT_LOAD='(1.0,-1.0)';
    'PT9B':
      PIN_NUMBER='(B3,0)';
      BIDIRECTIONAL='TRUE';
      INPUT_LOAD='(-0.01,0.01)';
      OUTPUT_LOAD='(1.0,-1.0)';
    'VCC'<3>:
      PIN_NUMBER='(0,P14)';
      PINUSE='POWER';
      NO_LOAD_CHECK='Both';
      NO_IO_CHECK='Both';
      NO_ASSERT_CHECK='TRUE';
      NO_DIR_CHECK='TRUE';
      ALLOW_CONNECT='TRUE';
    'VCC'<2>:
      PIN_NUMBER='(0,N1)';
      PINUSE='POWER';
      NO_LOAD_CHECK='Both';
      NO_IO_CHECK='Both';
      NO_ASSERT_CHECK='TRUE';
      NO_DIR_CHECK='TRUE';
      ALLOW_CONNECT='TRUE';
    'VCC'<1>:
      PIN_NUMBER='(0,A14)';
      PINUSE='POWER';
      NO_LOAD_CHECK='Both';
      NO_IO_CHECK='Both';
      NO_ASSERT_CHECK='TRUE';
      NO_DIR_CHECK='TRUE';
      ALLOW_CONNECT='TRUE';
    'VCC'<0>:
      PIN_NUMBER='(0,A1)';
      PINUSE='POWER';
      NO_LOAD_CHECK='Both';
      NO_IO_CHECK='Both';
      NO_ASSERT_CHECK='TRUE';
      NO_DIR_CHECK='TRUE';
      ALLOW_CONNECT='TRUE';
    'VCCIO0'<2>:
      PIN_NUMBER='(0,C5)';
      PINUSE='POWER';
      NO_LOAD_CHECK='Both';
      NO_IO_CHECK='Both';
      NO_ASSERT_CHECK='TRUE';
      NO_DIR_CHECK='TRUE';
      ALLOW_CONNECT='TRUE';
    'VCCIO0'<1>:
      PIN_NUMBER='(0,B10)';
      PINUSE='POWER';
      NO_LOAD_CHECK='Both';
      NO_IO_CHECK='Both';
      NO_ASSERT_CHECK='TRUE';
      NO_DIR_CHECK='TRUE';
      ALLOW_CONNECT='TRUE';
    'VCCIO0'<0>:
      PIN_NUMBER='(0,A8)';
      PINUSE='POWER';
      NO_LOAD_CHECK='Both';
      NO_IO_CHECK='Both';
      NO_ASSERT_CHECK='TRUE';
      NO_DIR_CHECK='TRUE';
      ALLOW_CONNECT='TRUE';
    'VCCIO1'<2>:
      PIN_NUMBER='(0,L12)';
      PINUSE='POWER';
      NO_LOAD_CHECK='Both';
      NO_IO_CHECK='Both';
      NO_ASSERT_CHECK='TRUE';
      NO_DIR_CHECK='TRUE';
      ALLOW_CONNECT='TRUE';
    'VCCIO1'<1>:
      PIN_NUMBER='(0,H14)';
      PINUSE='POWER';
      NO_LOAD_CHECK='Both';
      NO_IO_CHECK='Both';
      NO_ASSERT_CHECK='TRUE';
      NO_DIR_CHECK='TRUE';
      ALLOW_CONNECT='TRUE';
    'VCCIO1'<0>:
      PIN_NUMBER='(0,D14)';
      PINUSE='POWER';
      NO_LOAD_CHECK='Both';
      NO_IO_CHECK='Both';
      NO_ASSERT_CHECK='TRUE';
      NO_DIR_CHECK='TRUE';
      ALLOW_CONNECT='TRUE';
    'VCCIO2'<2>:
      PIN_NUMBER='(0,P1)';
      PINUSE='POWER';
      NO_LOAD_CHECK='Both';
      NO_IO_CHECK='Both';
      NO_ASSERT_CHECK='TRUE';
      NO_DIR_CHECK='TRUE';
      ALLOW_CONNECT='TRUE';
    'VCCIO2'<1>:
      PIN_NUMBER='(0,N11)';
      PINUSE='POWER';
      NO_LOAD_CHECK='Both';
      NO_IO_CHECK='Both';
      NO_ASSERT_CHECK='TRUE';
      NO_DIR_CHECK='TRUE';
      ALLOW_CONNECT='TRUE';
    'VCCIO2'<0>:
      PIN_NUMBER='(0,M6)';
      PINUSE='POWER';
      NO_LOAD_CHECK='Both';
      NO_IO_CHECK='Both';
      NO_ASSERT_CHECK='TRUE';
      NO_DIR_CHECK='TRUE';
      ALLOW_CONNECT='TRUE';
    'VCCIO3'<2>:
      PIN_NUMBER='(0,L1)';
      PINUSE='POWER';
      NO_LOAD_CHECK='Both';
      NO_IO_CHECK='Both';
      NO_ASSERT_CHECK='TRUE';
      NO_DIR_CHECK='TRUE';
      ALLOW_CONNECT='TRUE';
    'VCCIO3'<1>:
      PIN_NUMBER='(0,G1)';
      PINUSE='POWER';
      NO_LOAD_CHECK='Both';
      NO_IO_CHECK='Both';
      NO_ASSERT_CHECK='TRUE';
      NO_DIR_CHECK='TRUE';
      ALLOW_CONNECT='TRUE';
    'VCCIO3'<0>:
      PIN_NUMBER='(0,D3)';
      PINUSE='POWER';
      NO_LOAD_CHECK='Both';
      NO_IO_CHECK='Both';
      NO_ASSERT_CHECK='TRUE';
      NO_DIR_CHECK='TRUE';
      ALLOW_CONNECT='TRUE';
  end_pin;
  body
    PART_NAME='LCMXO2_A';
    PHYS_DES_PREFIX='U';
  end_body;
end_primitive;
primitive 'LCMXO2_A_256BGA';
  pin
    'PB3A':
      PIN_NUMBER='(P4,0,0)';
      BIDIRECTIONAL='TRUE';
      INPUT_LOAD='(-0.01,0.01)';
      OUTPUT_LOAD='(1.0,-1.0)';
    'PB3B':
      PIN_NUMBER='(T4,0,0)';
      BIDIRECTIONAL='TRUE';
      INPUT_LOAD='(-0.01,0.01)';
      OUTPUT_LOAD='(1.0,-1.0)';
    'PB3C':
      PIN_NUMBER='(T2,0,0)';
      BIDIRECTIONAL='TRUE';
      INPUT_LOAD='(-0.01,0.01)';
      OUTPUT_LOAD='(1.0,-1.0)';
    'PB3D':
      PIN_NUMBER='(R3,0,0)';
      BIDIRECTIONAL='TRUE';
      INPUT_LOAD='(-0.01,0.01)';
      OUTPUT_LOAD='(1.0,-1.0)';
    'PB5A_CSSPIN':
      PIN_NUMBER='(R5,0,0)';
      BIDIRECTIONAL='TRUE';
      INPUT_LOAD='(-0.01,0.01)';
      OUTPUT_LOAD='(1.0,-1.0)';
    'PB5B':
      PIN_NUMBER='(P5,0,0)';
      BIDIRECTIONAL='TRUE';
      INPUT_LOAD='(-0.01,0.01)';
      OUTPUT_LOAD='(1.0,-1.0)';
    'PB6A':
      PIN_NUMBER='(T5,0,0)';
      BIDIRECTIONAL='TRUE';
      INPUT_LOAD='(-0.01,0.01)';
      OUTPUT_LOAD='(1.0,-1.0)';
    'PB6B':
      PIN_NUMBER='(R6,0,0)';
      BIDIRECTIONAL='TRUE';
      INPUT_LOAD='(-0.01,0.01)';
      OUTPUT_LOAD='(1.0,-1.0)';
    'PB6C':
      PIN_NUMBER='(T3,0,0)';
      BIDIRECTIONAL='TRUE';
      INPUT_LOAD='(-0.01,0.01)';
      OUTPUT_LOAD='(1.0,-1.0)';
    'PB6D':
      PIN_NUMBER='(R4,0,0)';
      BIDIRECTIONAL='TRUE';
      INPUT_LOAD='(-0.01,0.01)';
      OUTPUT_LOAD='(1.0,-1.0)';
    'PB8A_MCLK_CCLK':
      PIN_NUMBER='(P6,0,0)';
      BIDIRECTIONAL='TRUE';
      INPUT_LOAD='(-0.01,0.01)';
      OUTPUT_LOAD='(1.0,-1.0)';
    'PB8B_SO_SPISO':
      PIN_NUMBER='(T6,0,0)';
      BIDIRECTIONAL='TRUE';
      INPUT_LOAD='(-0.01,0.01)';
      OUTPUT_LOAD='(1.0,-1.0)';
    'PB8C':
      PIN_NUMBER='(N6,0,0)';
      BIDIRECTIONAL='TRUE';
      INPUT_LOAD='(-0.01,0.01)';
      OUTPUT_LOAD='(1.0,-1.0)';
    'PB8D':
      PIN_NUMBER='(L7,0,0)';
      BIDIRECTIONAL='TRUE';
      INPUT_LOAD='(-0.01,0.01)';
      OUTPUT_LOAD='(1.0,-1.0)';
    'PB9A':
      PIN_NUMBER='(R7,0,0)';
      BIDIRECTIONAL='TRUE';
      INPUT_LOAD='(-0.01,0.01)';
      OUTPUT_LOAD='(1.0,-1.0)';
    'PB9B':
      PIN_NUMBER='(P7,0,0)';
      BIDIRECTIONAL='TRUE';
      INPUT_LOAD='(-0.01,0.01)';
      OUTPUT_LOAD='(1.0,-1.0)';
    'PB9C':
      PIN_NUMBER='(M7,0,0)';
      BIDIRECTIONAL='TRUE';
      INPUT_LOAD='(-0.01,0.01)';
      OUTPUT_LOAD='(1.0,-1.0)';
    'PB9D':
      PIN_NUMBER='(N7,0,0)';
      BIDIRECTIONAL='TRUE';
      INPUT_LOAD='(-0.01,0.01)';
      OUTPUT_LOAD='(1.0,-1.0)';
    'PB11A_PCLKT2_0':
      PIN_NUMBER='(T7,0,0)';
      BIDIRECTIONAL='TRUE';
      INPUT_LOAD='(-0.01,0.01)';
      OUTPUT_LOAD='(1.0,-1.0)';
    'PB11B_PCLKC2_0':
      PIN_NUMBER='(R8,0,0)';
      BIDIRECTIONAL='TRUE';
      INPUT_LOAD='(-0.01,0.01)';
      OUTPUT_LOAD='(1.0,-1.0)';
    'PB11C':
      PIN_NUMBER='(M6,0,0)';
      BIDIRECTIONAL='TRUE';
      INPUT_LOAD='(-0.01,0.01)';
      OUTPUT_LOAD='(1.0,-1.0)';
    'PB11D':
      PIN_NUMBER='(L8,0,0)';
      BIDIRECTIONAL='TRUE';
      INPUT_LOAD='(-0.01,0.01)';
      OUTPUT_LOAD='(1.0,-1.0)';
    'PB12A':
      PIN_NUMBER='(P8,0,0)';
      BIDIRECTIONAL='TRUE';
      INPUT_LOAD='(-0.01,0.01)';
      OUTPUT_LOAD='(1.0,-1.0)';
    'PB12B':
      PIN_NUMBER='(T8,0,0)';
      BIDIRECTIONAL='TRUE';
      INPUT_LOAD='(-0.01,0.01)';
      OUTPUT_LOAD='(1.0,-1.0)';
    'PB12C':
      PIN_NUMBER='(N8,0,0)';
      BIDIRECTIONAL='TRUE';
      INPUT_LOAD='(-0.01,0.01)';
      OUTPUT_LOAD='(1.0,-1.0)';
    'PB12D':
      PIN_NUMBER='(L9,0,0)';
      BIDIRECTIONAL='TRUE';
      INPUT_LOAD='(-0.01,0.01)';
      OUTPUT_LOAD='(1.0,-1.0)';
    'PB16A_PCLKT2_1':
      PIN_NUMBER='(T9,0,0)';
      BIDIRECTIONAL='TRUE';
      INPUT_LOAD='(-0.01,0.01)';
      OUTPUT_LOAD='(1.0,-1.0)';
    'PB16B_PCLKC2_1':
      PIN_NUMBER='(P9,0,0)';
      BIDIRECTIONAL='TRUE';
      INPUT_LOAD='(-0.01,0.01)';
      OUTPUT_LOAD='(1.0,-1.0)';
    'PB16C':
      PIN_NUMBER='(M8,0,0)';
      BIDIRECTIONAL='TRUE';
      INPUT_LOAD='(-0.01,0.01)';
      OUTPUT_LOAD='(1.0,-1.0)';
    'PB16D':
      PIN_NUMBER='(N9,0,0)';
      BIDIRECTIONAL='TRUE';
      INPUT_LOAD='(-0.01,0.01)';
      OUTPUT_LOAD='(1.0,-1.0)';
    'PB18A':
      PIN_NUMBER='(R9,0,0)';
      BIDIRECTIONAL='TRUE';
      INPUT_LOAD='(-0.01,0.01)';
      OUTPUT_LOAD='(1.0,-1.0)';
    'PB18B':
      PIN_NUMBER='(T10,0,0)';
      BIDIRECTIONAL='TRUE';
      INPUT_LOAD='(-0.01,0.01)';
      OUTPUT_LOAD='(1.0,-1.0)';
    'PB18C':
      PIN_NUMBER='(M9,0,0)';
      BIDIRECTIONAL='TRUE';
      INPUT_LOAD='(-0.01,0.01)';
      OUTPUT_LOAD='(1.0,-1.0)';
    'PB18D':
      PIN_NUMBER='(L10,0,0)';
      BIDIRECTIONAL='TRUE';
      INPUT_LOAD='(-0.01,0.01)';
      OUTPUT_LOAD='(1.0,-1.0)';
    'PB19A':
      PIN_NUMBER='(P10,0,0)';
      BIDIRECTIONAL='TRUE';
      INPUT_LOAD='(-0.01,0.01)';
      OUTPUT_LOAD='(1.0,-1.0)';
    'PB19B':
      PIN_NUMBER='(R10,0,0)';
      BIDIRECTIONAL='TRUE';
      INPUT_LOAD='(-0.01,0.01)';
      OUTPUT_LOAD='(1.0,-1.0)';
    'PB19C':
      PIN_NUMBER='(N10,0,0)';
      BIDIRECTIONAL='TRUE';
      INPUT_LOAD='(-0.01,0.01)';
      OUTPUT_LOAD='(1.0,-1.0)';
    'PB19D':
      PIN_NUMBER='(M11,0,0)';
      BIDIRECTIONAL='TRUE';
      INPUT_LOAD='(-0.01,0.01)';
      OUTPUT_LOAD='(1.0,-1.0)';
    'PB21A':
      PIN_NUMBER='(T11,0,0)';
      BIDIRECTIONAL='TRUE';
      INPUT_LOAD='(-0.01,0.01)';
      OUTPUT_LOAD='(1.0,-1.0)';
    'PB21B':
      PIN_NUMBER='(P11,0,0)';
      BIDIRECTIONAL='TRUE';
      INPUT_LOAD='(-0.01,0.01)';
      OUTPUT_LOAD='(1.0,-1.0)';
    'PB21C':
      PIN_NUMBER='(M10,0,0)';
      BIDIRECTIONAL='TRUE';
      INPUT_LOAD='(-0.01,0.01)';
      OUTPUT_LOAD='(1.0,-1.0)';
    'PB21D':
      PIN_NUMBER='(N11,0,0)';
      BIDIRECTIONAL='TRUE';
      INPUT_LOAD='(-0.01,0.01)';
      OUTPUT_LOAD='(1.0,-1.0)';
    'PB22A':
      PIN_NUMBER='(R11,0,0)';
      BIDIRECTIONAL='TRUE';
      INPUT_LOAD='(-0.01,0.01)';
      OUTPUT_LOAD='(1.0,-1.0)';
    'PB22B':
      PIN_NUMBER='(T12,0,0)';
      BIDIRECTIONAL='TRUE';
      INPUT_LOAD='(-0.01,0.01)';
      OUTPUT_LOAD='(1.0,-1.0)';
    'PB22C':
      PIN_NUMBER='(R13,0,0)';
      BIDIRECTIONAL='TRUE';
      INPUT_LOAD='(-0.01,0.01)';
      OUTPUT_LOAD='(1.0,-1.0)';
    'PB22D':
      PIN_NUMBER='(T14,0,0)';
      BIDIRECTIONAL='TRUE';
      INPUT_LOAD='(-0.01,0.01)';
      OUTPUT_LOAD='(1.0,-1.0)';
    'PB24A':
      PIN_NUMBER='(P12,0,0)';
      BIDIRECTIONAL='TRUE';
      INPUT_LOAD='(-0.01,0.01)';
      OUTPUT_LOAD='(1.0,-1.0)';
    'PB24B':
      PIN_NUMBER='(T13,0,0)';
      BIDIRECTIONAL='TRUE';
      INPUT_LOAD='(-0.01,0.01)';
      OUTPUT_LOAD='(1.0,-1.0)';
    'PB25A_SN':
      PIN_NUMBER='(R12,0,0)';
      BIDIRECTIONAL='TRUE';
      INPUT_LOAD='(-0.01,0.01)';
      OUTPUT_LOAD='(1.0,-1.0)';
    'PB25B_SI_SISPI':
      PIN_NUMBER='(P13,0,0)';
      BIDIRECTIONAL='TRUE';
      INPUT_LOAD='(-0.01,0.01)';
      OUTPUT_LOAD='(1.0,-1.0)';
    'PB25C':
      PIN_NUMBER='(T15,0,0)';
      BIDIRECTIONAL='TRUE';
      INPUT_LOAD='(-0.01,0.01)';
      OUTPUT_LOAD='(1.0,-1.0)';
    'PB25D':
      PIN_NUMBER='(R14,0,0)';
      BIDIRECTIONAL='TRUE';
      INPUT_LOAD='(-0.01,0.01)';
      OUTPUT_LOAD='(1.0,-1.0)';
    'PL1A_L_GPLLT_FB':
      PIN_NUMBER='(D3,0,0)';
      BIDIRECTIONAL='TRUE';
      INPUT_LOAD='(-0.01,0.01)';
      OUTPUT_LOAD='(1.0,-1.0)';
    'PL1B_L_GPLLC_FB':
      PIN_NUMBER='(D1,0,0)';
      BIDIRECTIONAL='TRUE';
      INPUT_LOAD='(-0.01,0.01)';
      OUTPUT_LOAD='(1.0,-1.0)';
    'PL1C':
      PIN_NUMBER='(B1,0,0)';
      BIDIRECTIONAL='TRUE';
      INPUT_LOAD='(-0.01,0.01)';
      OUTPUT_LOAD='(1.0,-1.0)';
    'PL1D':
      PIN_NUMBER='(C2,0,0)';
      BIDIRECTIONAL='TRUE';
      INPUT_LOAD='(-0.01,0.01)';
      OUTPUT_LOAD='(1.0,-1.0)';
    'PL2A_L_GPLLT_IN':
      PIN_NUMBER='(E2,0,0)';
      BIDIRECTIONAL='TRUE';
      INPUT_LOAD='(-0.01,0.01)';
      OUTPUT_LOAD='(1.0,-1.0)';
    'PL2B_L_GPLLC_IN':
      PIN_NUMBER='(E3,0,0)';
      BIDIRECTIONAL='TRUE';
      INPUT_LOAD='(-0.01,0.01)';
      OUTPUT_LOAD='(1.0,-1.0)';
    'PL2C':
      PIN_NUMBER='(C1,0,0)';
      BIDIRECTIONAL='TRUE';
      INPUT_LOAD='(-0.01,0.01)';
      OUTPUT_LOAD='(1.0,-1.0)';
    'PL2D':
      PIN_NUMBER='(D2,0,0)';
      BIDIRECTIONAL='TRUE';
      INPUT_LOAD='(-0.01,0.01)';
      OUTPUT_LOAD='(1.0,-1.0)';
    'PL3A_PCLKT5_0':
      PIN_NUMBER='(E1,0,0)';
      BIDIRECTIONAL='TRUE';
      INPUT_LOAD='(-0.01,0.01)';
      OUTPUT_LOAD='(1.0,-1.0)';
    'PL3B_PCLKC5_0':
      PIN_NUMBER='(F2,0,0)';
      BIDIRECTIONAL='TRUE';
      INPUT_LOAD='(-0.01,0.01)';
      OUTPUT_LOAD='(1.0,-1.0)';
    'PL3C':
      PIN_NUMBER='(F4,0,0)';
      BIDIRECTIONAL='TRUE';
      INPUT_LOAD='(-0.01,0.01)';
      OUTPUT_LOAD='(1.0,-1.0)';
    'PL3D':
      PIN_NUMBER='(G6,0,0)';
      BIDIRECTIONAL='TRUE';
      INPUT_LOAD='(-0.01,0.01)';
      OUTPUT_LOAD='(1.0,-1.0)';
    'PL4A':
      PIN_NUMBER='(F3,0,0)';
      BIDIRECTIONAL='TRUE';
      INPUT_LOAD='(-0.01,0.01)';
      OUTPUT_LOAD='(1.0,-1.0)';
    'PL4B':
      PIN_NUMBER='(F1,0,0)';
      BIDIRECTIONAL='TRUE';
      INPUT_LOAD='(-0.01,0.01)';
      OUTPUT_LOAD='(1.0,-1.0)';
    'PL4C':
      PIN_NUMBER='(G5,0,0)';
      BIDIRECTIONAL='TRUE';
      INPUT_LOAD='(-0.01,0.01)';
      OUTPUT_LOAD='(1.0,-1.0)';
    'PL4D':
      PIN_NUMBER='(G4,0,0)';
      BIDIRECTIONAL='TRUE';
      INPUT_LOAD='(-0.01,0.01)';
      OUTPUT_LOAD='(1.0,-1.0)';
    'PL5A':
      PIN_NUMBER='(G2,0,0)';
      BIDIRECTIONAL='TRUE';
      INPUT_LOAD='(-0.01,0.01)';
      OUTPUT_LOAD='(1.0,-1.0)';
    'PL5B':
      PIN_NUMBER='(G3,0,0)';
      BIDIRECTIONAL='TRUE';
      INPUT_LOAD='(-0.01,0.01)';
      OUTPUT_LOAD='(1.0,-1.0)';
    'PL5C':
      PIN_NUMBER='(F5,0,0)';
      BIDIRECTIONAL='TRUE';
      INPUT_LOAD='(-0.01,0.01)';
      OUTPUT_LOAD='(1.0,-1.0)';
    'PL5D':
      PIN_NUMBER='(H6,0,0)';
      BIDIRECTIONAL='TRUE';
      INPUT_LOAD='(-0.01,0.01)';
      OUTPUT_LOAD='(1.0,-1.0)';
    'PL6A':
      PIN_NUMBER='(G1,0,0)';
      BIDIRECTIONAL='TRUE';
      INPUT_LOAD='(-0.01,0.01)';
      OUTPUT_LOAD='(1.0,-1.0)';
    'PL6B':
      PIN_NUMBER='(H2,0,0)';
      BIDIRECTIONAL='TRUE';
      INPUT_LOAD='(-0.01,0.01)';
      OUTPUT_LOAD='(1.0,-1.0)';
    'PL6C':
      PIN_NUMBER='(H4,0,0)';
      BIDIRECTIONAL='TRUE';
      INPUT_LOAD='(-0.01,0.01)';
      OUTPUT_LOAD='(1.0,-1.0)';
    'PL6D':
      PIN_NUMBER='(J6,0,0)';
      BIDIRECTIONAL='TRUE';
      INPUT_LOAD='(-0.01,0.01)';
      OUTPUT_LOAD='(1.0,-1.0)';
    'PL7A':
      PIN_NUMBER='(H3,0,0)';
      BIDIRECTIONAL='TRUE';
      INPUT_LOAD='(-0.01,0.01)';
      OUTPUT_LOAD='(1.0,-1.0)';
    'PL7B':
      PIN_NUMBER='(H1,0,0)';
      BIDIRECTIONAL='TRUE';
      INPUT_LOAD='(-0.01,0.01)';
      OUTPUT_LOAD='(1.0,-1.0)';
    'PL7C_PCLKT4_0':
      PIN_NUMBER='(J1,0,0)';
      BIDIRECTIONAL='TRUE';
      INPUT_LOAD='(-0.01,0.01)';
      OUTPUT_LOAD='(1.0,-1.0)';
    'PL7D_PCLKC4_0':
      PIN_NUMBER='(J3,0,0)';
      BIDIRECTIONAL='TRUE';
      INPUT_LOAD='(-0.01,0.01)';
      OUTPUT_LOAD='(1.0,-1.0)';
    'PL9A':
      PIN_NUMBER='(J2,0,0)';
      BIDIRECTIONAL='TRUE';
      INPUT_LOAD='(-0.01,0.01)';
      OUTPUT_LOAD='(1.0,-1.0)';
    'PL9B':
      PIN_NUMBER='(K1,0,0)';
      BIDIRECTIONAL='TRUE';
      INPUT_LOAD='(-0.01,0.01)';
      OUTPUT_LOAD='(1.0,-1.0)';
    'PL9C':
      PIN_NUMBER='(H5,0,0)';
      BIDIRECTIONAL='TRUE';
      INPUT_LOAD='(-0.01,0.01)';
      OUTPUT_LOAD='(1.0,-1.0)';
    'PL9D':
      PIN_NUMBER='(J4,0,0)';
      BIDIRECTIONAL='TRUE';
      INPUT_LOAD='(-0.01,0.01)';
      OUTPUT_LOAD='(1.0,-1.0)';
    'PL10A':
      PIN_NUMBER='(K3,0,0)';
      BIDIRECTIONAL='TRUE';
      INPUT_LOAD='(-0.01,0.01)';
      OUTPUT_LOAD='(1.0,-1.0)';
    'PL10B':
      PIN_NUMBER='(K2,0,0)';
      BIDIRECTIONAL='TRUE';
      INPUT_LOAD='(-0.01,0.01)';
      OUTPUT_LOAD='(1.0,-1.0)';
    'PL10C':
      PIN_NUMBER='(J5,0,0)';
      BIDIRECTIONAL='TRUE';
      INPUT_LOAD='(-0.01,0.01)';
      OUTPUT_LOAD='(1.0,-1.0)';
    'PL10D':
      PIN_NUMBER='(K6,0,0)';
      BIDIRECTIONAL='TRUE';
      INPUT_LOAD='(-0.01,0.01)';
      OUTPUT_LOAD='(1.0,-1.0)';
    'PL11A':
      PIN_NUMBER='(L1,0,0)';
      BIDIRECTIONAL='TRUE';
      INPUT_LOAD='(-0.01,0.01)';
      OUTPUT_LOAD='(1.0,-1.0)';
    'PL11B':
      PIN_NUMBER='(L3,0,0)';
      BIDIRECTIONAL='TRUE';
      INPUT_LOAD='(-0.01,0.01)';
      OUTPUT_LOAD='(1.0,-1.0)';
    'PL11C':
      PIN_NUMBER='(K4,0,0)';
      BIDIRECTIONAL='TRUE';
      INPUT_LOAD='(-0.01,0.01)';
      OUTPUT_LOAD='(1.0,-1.0)';
    'PL11D':
      PIN_NUMBER='(L5,0,0)';
      BIDIRECTIONAL='TRUE';
      INPUT_LOAD='(-0.01,0.01)';
      OUTPUT_LOAD='(1.0,-1.0)';
    'PL12A_PCLKT3_0':
      PIN_NUMBER='(L2,0,0)';
      BIDIRECTIONAL='TRUE';
      INPUT_LOAD='(-0.01,0.01)';
      OUTPUT_LOAD='(1.0,-1.0)';
    'PL12B_PCLKC3_0':
      PIN_NUMBER='(M1,0,0)';
      BIDIRECTIONAL='TRUE';
      INPUT_LOAD='(-0.01,0.01)';
      OUTPUT_LOAD='(1.0,-1.0)';
    'PL12C':
      PIN_NUMBER='(K5,0,0)';
      BIDIRECTIONAL='TRUE';
      INPUT_LOAD='(-0.01,0.01)';
      OUTPUT_LOAD='(1.0,-1.0)';
    'PL12D':
      PIN_NUMBER='(L4,0,0)';
      BIDIRECTIONAL='TRUE';
      INPUT_LOAD='(-0.01,0.01)';
      OUTPUT_LOAD='(1.0,-1.0)';
    'PL13A':
      PIN_NUMBER='(M3,0,0)';
      BIDIRECTIONAL='TRUE';
      INPUT_LOAD='(-0.01,0.01)';
      OUTPUT_LOAD='(1.0,-1.0)';
    'PL13B':
      PIN_NUMBER='(N1,0,0)';
      BIDIRECTIONAL='TRUE';
      INPUT_LOAD='(-0.01,0.01)';
      OUTPUT_LOAD='(1.0,-1.0)';
    'PL13C':
      PIN_NUMBER='(N2,0,0)';
      BIDIRECTIONAL='TRUE';
      INPUT_LOAD='(-0.01,0.01)';
      OUTPUT_LOAD='(1.0,-1.0)';
    'PL13D':
      PIN_NUMBER='(P1,0,0)';
      BIDIRECTIONAL='TRUE';
      INPUT_LOAD='(-0.01,0.01)';
      OUTPUT_LOAD='(1.0,-1.0)';
    'PL14A':
      PIN_NUMBER='(M2,0,0)';
      BIDIRECTIONAL='TRUE';
      INPUT_LOAD='(-0.01,0.01)';
      OUTPUT_LOAD='(1.0,-1.0)';
    'PL14B':
      PIN_NUMBER='(N3,0,0)';
      BIDIRECTIONAL='TRUE';
      INPUT_LOAD='(-0.01,0.01)';
      OUTPUT_LOAD='(1.0,-1.0)';
    'PL14C':
      PIN_NUMBER='(R1,0,0)';
      BIDIRECTIONAL='TRUE';
      INPUT_LOAD='(-0.01,0.01)';
      OUTPUT_LOAD='(1.0,-1.0)';
    'PL14D':
      PIN_NUMBER='(P2,0,0)';
      BIDIRECTIONAL='TRUE';
      INPUT_LOAD='(-0.01,0.01)';
      OUTPUT_LOAD='(1.0,-1.0)';
    'PR1A':
      PIN_NUMBER='(0,D14,0)';
      BIDIRECTIONAL='TRUE';
      INPUT_LOAD='(-0.01,0.01)';
      OUTPUT_LOAD='(1.0,-1.0)';
    'PR1B':
      PIN_NUMBER='(0,E15,0)';
      BIDIRECTIONAL='TRUE';
      INPUT_LOAD='(-0.01,0.01)';
      OUTPUT_LOAD='(1.0,-1.0)';
    'PR1C':
      PIN_NUMBER='(0,C15,0)';
      BIDIRECTIONAL='TRUE';
      INPUT_LOAD='(-0.01,0.01)';
      OUTPUT_LOAD='(1.0,-1.0)';
    'PR1D':
      PIN_NUMBER='(0,B16,0)';
      BIDIRECTIONAL='TRUE';
      INPUT_LOAD='(-0.01,0.01)';
      OUTPUT_LOAD='(1.0,-1.0)';
    'PR2A':
      PIN_NUMBER='(0,D16,0)';
      BIDIRECTIONAL='TRUE';
      INPUT_LOAD='(-0.01,0.01)';
      OUTPUT_LOAD='(1.0,-1.0)';
    'PR2B':
      PIN_NUMBER='(0,E14,0)';
      BIDIRECTIONAL='TRUE';
      INPUT_LOAD='(-0.01,0.01)';
      OUTPUT_LOAD='(1.0,-1.0)';
    'PR2C':
      PIN_NUMBER='(0,C16,0)';
      BIDIRECTIONAL='TRUE';
      INPUT_LOAD='(-0.01,0.01)';
      OUTPUT_LOAD='(1.0,-1.0)';
    'PR2D':
      PIN_NUMBER='(0,D15,0)';
      BIDIRECTIONAL='TRUE';
      INPUT_LOAD='(-0.01,0.01)';
      OUTPUT_LOAD='(1.0,-1.0)';
    'PR3A':
      PIN_NUMBER='(0,E16,0)';
      BIDIRECTIONAL='TRUE';
      INPUT_LOAD='(-0.01,0.01)';
      OUTPUT_LOAD='(1.0,-1.0)';
    'PR3B':
      PIN_NUMBER='(0,F15,0)';
      BIDIRECTIONAL='TRUE';
      INPUT_LOAD='(-0.01,0.01)';
      OUTPUT_LOAD='(1.0,-1.0)';
    'PR3C':
      PIN_NUMBER='(0,F13,0)';
      BIDIRECTIONAL='TRUE';
      INPUT_LOAD='(-0.01,0.01)';
      OUTPUT_LOAD='(1.0,-1.0)';
    'PR3D':
      PIN_NUMBER='(0,G12,0)';
      BIDIRECTIONAL='TRUE';
      INPUT_LOAD='(-0.01,0.01)';
      OUTPUT_LOAD='(1.0,-1.0)';
    'PR4A':
      PIN_NUMBER='(0,F14,0)';
      BIDIRECTIONAL='TRUE';
      INPUT_LOAD='(-0.01,0.01)';
      OUTPUT_LOAD='(1.0,-1.0)';
    'PR4B':
      PIN_NUMBER='(0,F16,0)';
      BIDIRECTIONAL='TRUE';
      INPUT_LOAD='(-0.01,0.01)';
      OUTPUT_LOAD='(1.0,-1.0)';
    'PR4C':
      PIN_NUMBER='(0,F12,0)';
      BIDIRECTIONAL='TRUE';
      INPUT_LOAD='(-0.01,0.01)';
      OUTPUT_LOAD='(1.0,-1.0)';
    'PR4D':
      PIN_NUMBER='(0,G13,0)';
      BIDIRECTIONAL='TRUE';
      INPUT_LOAD='(-0.01,0.01)';
      OUTPUT_LOAD='(1.0,-1.0)';
    'PR5A':
      PIN_NUMBER='(0,G15,0)';
      BIDIRECTIONAL='TRUE';
      INPUT_LOAD='(-0.01,0.01)';
      OUTPUT_LOAD='(1.0,-1.0)';
    'PR5B':
      PIN_NUMBER='(0,G14,0)';
      BIDIRECTIONAL='TRUE';
      INPUT_LOAD='(-0.01,0.01)';
      OUTPUT_LOAD='(1.0,-1.0)';
    'PR5C':
      PIN_NUMBER='(0,G11,0)';
      BIDIRECTIONAL='TRUE';
      INPUT_LOAD='(-0.01,0.01)';
      OUTPUT_LOAD='(1.0,-1.0)';
    'PR5D':
      PIN_NUMBER='(0,H12,0)';
      BIDIRECTIONAL='TRUE';
      INPUT_LOAD='(-0.01,0.01)';
      OUTPUT_LOAD='(1.0,-1.0)';
    'PR6A':
      PIN_NUMBER='(0,G16,0)';
      BIDIRECTIONAL='TRUE';
      INPUT_LOAD='(-0.01,0.01)';
      OUTPUT_LOAD='(1.0,-1.0)';
    'PR6B':
      PIN_NUMBER='(0,H15,0)';
      BIDIRECTIONAL='TRUE';
      INPUT_LOAD='(-0.01,0.01)';
      OUTPUT_LOAD='(1.0,-1.0)';
    'PR6C':
      PIN_NUMBER='(0,H13,0)';
      BIDIRECTIONAL='TRUE';
      INPUT_LOAD='(-0.01,0.01)';
      OUTPUT_LOAD='(1.0,-1.0)';
    'PR6D':
      PIN_NUMBER='(0,J12,0)';
      BIDIRECTIONAL='TRUE';
      INPUT_LOAD='(-0.01,0.01)';
      OUTPUT_LOAD='(1.0,-1.0)';
    'PR7A_PCLKT1_0':
      PIN_NUMBER='(0,H14,0)';
      BIDIRECTIONAL='TRUE';
      INPUT_LOAD='(-0.01,0.01)';
      OUTPUT_LOAD='(1.0,-1.0)';
    'PR7B_PCLKC1_0':
      PIN_NUMBER='(0,H16,0)';
      BIDIRECTIONAL='TRUE';
      INPUT_LOAD='(-0.01,0.01)';
      OUTPUT_LOAD='(1.0,-1.0)';
    'PR7C':
      PIN_NUMBER='(0,J16,0)';
      BIDIRECTIONAL='TRUE';
      INPUT_LOAD='(-0.01,0.01)';
      OUTPUT_LOAD='(1.0,-1.0)';
    'PR7D':
      PIN_NUMBER='(0,J14,0)';
      BIDIRECTIONAL='TRUE';
      INPUT_LOAD='(-0.01,0.01)';
      OUTPUT_LOAD='(1.0,-1.0)';
    'PR9A':
      PIN_NUMBER='(0,J15,0)';
      BIDIRECTIONAL='TRUE';
      INPUT_LOAD='(-0.01,0.01)';
      OUTPUT_LOAD='(1.0,-1.0)';
    'PR9B':
      PIN_NUMBER='(0,K16,0)';
      BIDIRECTIONAL='TRUE';
      INPUT_LOAD='(-0.01,0.01)';
      OUTPUT_LOAD='(1.0,-1.0)';
    'PR9C':
      PIN_NUMBER='(0,H11,0)';
      BIDIRECTIONAL='TRUE';
      INPUT_LOAD='(-0.01,0.01)';
      OUTPUT_LOAD='(1.0,-1.0)';
    'PR9D':
      PIN_NUMBER='(0,J13,0)';
      BIDIRECTIONAL='TRUE';
      INPUT_LOAD='(-0.01,0.01)';
      OUTPUT_LOAD='(1.0,-1.0)';
    'PR10A':
      PIN_NUMBER='(0,K14,0)';
      BIDIRECTIONAL='TRUE';
      INPUT_LOAD='(-0.01,0.01)';
      OUTPUT_LOAD='(1.0,-1.0)';
    'PR10B':
      PIN_NUMBER='(0,K15,0)';
      BIDIRECTIONAL='TRUE';
      INPUT_LOAD='(-0.01,0.01)';
      OUTPUT_LOAD='(1.0,-1.0)';
    'PR10C':
      PIN_NUMBER='(0,J11,0)';
      BIDIRECTIONAL='TRUE';
      INPUT_LOAD='(-0.01,0.01)';
      OUTPUT_LOAD='(1.0,-1.0)';
    'PR10D':
      PIN_NUMBER='(0,L12,0)';
      BIDIRECTIONAL='TRUE';
      INPUT_LOAD='(-0.01,0.01)';
      OUTPUT_LOAD='(1.0,-1.0)';
    'PR11A':
      PIN_NUMBER='(0,L16,0)';
      BIDIRECTIONAL='TRUE';
      INPUT_LOAD='(-0.01,0.01)';
      OUTPUT_LOAD='(1.0,-1.0)';
    'PR11B':
      PIN_NUMBER='(0,L14,0)';
      BIDIRECTIONAL='TRUE';
      INPUT_LOAD='(-0.01,0.01)';
      OUTPUT_LOAD='(1.0,-1.0)';
    'PR11C':
      PIN_NUMBER='(0,K13,0)';
      BIDIRECTIONAL='TRUE';
      INPUT_LOAD='(-0.01,0.01)';
      OUTPUT_LOAD='(1.0,-1.0)';
    'PR11D':
      PIN_NUMBER='(0,K12,0)';
      BIDIRECTIONAL='TRUE';
      INPUT_LOAD='(-0.01,0.01)';
      OUTPUT_LOAD='(1.0,-1.0)';
    'PR12A':
      PIN_NUMBER='(0,L15,0)';
      BIDIRECTIONAL='TRUE';
      INPUT_LOAD='(-0.01,0.01)';
      OUTPUT_LOAD='(1.0,-1.0)';
    'PR12B':
      PIN_NUMBER='(0,M16,0)';
      BIDIRECTIONAL='TRUE';
      INPUT_LOAD='(-0.01,0.01)';
      OUTPUT_LOAD='(1.0,-1.0)';
    'PR12C':
      PIN_NUMBER='(0,K11,0)';
      BIDIRECTIONAL='TRUE';
      INPUT_LOAD='(-0.01,0.01)';
      OUTPUT_LOAD='(1.0,-1.0)';
    'PR12D':
      PIN_NUMBER='(0,L13,0)';
      BIDIRECTIONAL='TRUE';
      INPUT_LOAD='(-0.01,0.01)';
      OUTPUT_LOAD='(1.0,-1.0)';
    'PR13A':
      PIN_NUMBER='(0,M14,0)';
      BIDIRECTIONAL='TRUE';
      INPUT_LOAD='(-0.01,0.01)';
      OUTPUT_LOAD='(1.0,-1.0)';
    'PR13B':
      PIN_NUMBER='(0,M15,0)';
      BIDIRECTIONAL='TRUE';
      INPUT_LOAD='(-0.01,0.01)';
      OUTPUT_LOAD='(1.0,-1.0)';
    'PR13C':
      PIN_NUMBER='(0,N15,0)';
      BIDIRECTIONAL='TRUE';
      INPUT_LOAD='(-0.01,0.01)';
      OUTPUT_LOAD='(1.0,-1.0)';
    'PR13D':
      PIN_NUMBER='(0,P16,0)';
      BIDIRECTIONAL='TRUE';
      INPUT_LOAD='(-0.01,0.01)';
      OUTPUT_LOAD='(1.0,-1.0)';
    'PR14A':
      PIN_NUMBER='(0,N16,0)';
      BIDIRECTIONAL='TRUE';
      INPUT_LOAD='(-0.01,0.01)';
      OUTPUT_LOAD='(1.0,-1.0)';
    'PR14B':
      PIN_NUMBER='(0,N14,0)';
      BIDIRECTIONAL='TRUE';
      INPUT_LOAD='(-0.01,0.01)';
      OUTPUT_LOAD='(1.0,-1.0)';
    'PR14C':
      PIN_NUMBER='(0,P15,0)';
      BIDIRECTIONAL='TRUE';
      INPUT_LOAD='(-0.01,0.01)';
      OUTPUT_LOAD='(1.0,-1.0)';
    'PR14D':
      PIN_NUMBER='(0,R16,0)';
      BIDIRECTIONAL='TRUE';
      INPUT_LOAD='(-0.01,0.01)';
      OUTPUT_LOAD='(1.0,-1.0)';
    'PT9A':
      PIN_NUMBER='(0,C4,0)';
      BIDIRECTIONAL='TRUE';
      INPUT_LOAD='(-0.01,0.01)';
      OUTPUT_LOAD='(1.0,-1.0)';
    'PT9B':
      PIN_NUMBER='(0,B5,0)';
      BIDIRECTIONAL='TRUE';
      INPUT_LOAD='(-0.01,0.01)';
      OUTPUT_LOAD='(1.0,-1.0)';
    'PT9C':
      PIN_NUMBER='(0,B3,0)';
      BIDIRECTIONAL='TRUE';
      INPUT_LOAD='(-0.01,0.01)';
      OUTPUT_LOAD='(1.0,-1.0)';
    'PT10A':
      PIN_NUMBER='(0,A4,0)';
      BIDIRECTIONAL='TRUE';
      INPUT_LOAD='(-0.01,0.01)';
      OUTPUT_LOAD='(1.0,-1.0)';
    'PT10B':
      PIN_NUMBER='(0,C5,0)';
      BIDIRECTIONAL='TRUE';
      INPUT_LOAD='(-0.01,0.01)';
      OUTPUT_LOAD='(1.0,-1.0)';
    'PT11A':
      PIN_NUMBER='(0,A5,0)';
      BIDIRECTIONAL='TRUE';
      INPUT_LOAD='(-0.01,0.01)';
      OUTPUT_LOAD='(1.0,-1.0)';
    'PT11B':
      PIN_NUMBER='(0,B6,0)';
      BIDIRECTIONAL='TRUE';
      INPUT_LOAD='(-0.01,0.01)';
      OUTPUT_LOAD='(1.0,-1.0)';
    'PT11C':
      PIN_NUMBER='(0,A3,0)';
      BIDIRECTIONAL='TRUE';
      INPUT_LOAD='(-0.01,0.01)';
      OUTPUT_LOAD='(1.0,-1.0)';
    'PT11D':
      PIN_NUMBER='(0,B4,0)';
      BIDIRECTIONAL='TRUE';
      INPUT_LOAD='(-0.01,0.01)';
      OUTPUT_LOAD='(1.0,-1.0)';
    'PT12A':
      PIN_NUMBER='(0,D6,0)';
      BIDIRECTIONAL='TRUE';
      INPUT_LOAD='(-0.01,0.01)';
      OUTPUT_LOAD='(1.0,-1.0)';
    'PT12B':
      PIN_NUMBER='(0,E7,0)';
      BIDIRECTIONAL='TRUE';
      INPUT_LOAD='(-0.01,0.01)';
      OUTPUT_LOAD='(1.0,-1.0)';
    'PT12C_TDO':
      PIN_NUMBER='(0,C6,0)';
      BIDIRECTIONAL='TRUE';
      INPUT_LOAD='(-0.01,0.01)';
      OUTPUT_LOAD='(1.0,-1.0)';
    'PT12D_TDI':
      PIN_NUMBER='(0,A6,0)';
      BIDIRECTIONAL='TRUE';
      INPUT_LOAD='(-0.01,0.01)';
      OUTPUT_LOAD='(1.0,-1.0)';
    'PT13A':
      PIN_NUMBER='(0,B7,0)';
      BIDIRECTIONAL='TRUE';
      INPUT_LOAD='(-0.01,0.01)';
      OUTPUT_LOAD='(1.0,-1.0)';
    'PT13B':
      PIN_NUMBER='(0,C7,0)';
      BIDIRECTIONAL='TRUE';
      INPUT_LOAD='(-0.01,0.01)';
      OUTPUT_LOAD='(1.0,-1.0)';
    'PT13C':
      PIN_NUMBER='(0,E6,0)';
      BIDIRECTIONAL='TRUE';
      INPUT_LOAD='(-0.01,0.01)';
      OUTPUT_LOAD='(1.0,-1.0)';
    'PT13D':
      PIN_NUMBER='(0,D7,0)';
      BIDIRECTIONAL='TRUE';
      INPUT_LOAD='(-0.01,0.01)';
      OUTPUT_LOAD='(1.0,-1.0)';
    'PT16A':
      PIN_NUMBER='(0,F7,0)';
      BIDIRECTIONAL='TRUE';
      INPUT_LOAD='(-0.01,0.01)';
      OUTPUT_LOAD='(1.0,-1.0)';
    'PT16B':
      PIN_NUMBER='(0,E8,0)';
      BIDIRECTIONAL='TRUE';
      INPUT_LOAD='(-0.01,0.01)';
      OUTPUT_LOAD='(1.0,-1.0)';
    'PT16C_TCK':
      PIN_NUMBER='(0,A7,0)';
      BIDIRECTIONAL='TRUE';
      INPUT_LOAD='(-0.01,0.01)';
      OUTPUT_LOAD='(1.0,-1.0)';
    'PT16D_TMS':
      PIN_NUMBER='(0,B8,0)';
      BIDIRECTIONAL='TRUE';
      INPUT_LOAD='(-0.01,0.01)';
      OUTPUT_LOAD='(1.0,-1.0)';
    'PT17A_PCLKT0_1':
      PIN_NUMBER='(0,C8,0)';
      BIDIRECTIONAL='TRUE';
      INPUT_LOAD='(-0.01,0.01)';
      OUTPUT_LOAD='(1.0,-1.0)';
    'PT17B_PCLKC0_1':
      PIN_NUMBER='(0,A8,0)';
      BIDIRECTIONAL='TRUE';
      INPUT_LOAD='(-0.01,0.01)';
      OUTPUT_LOAD='(1.0,-1.0)';
    'PT17C':
      PIN_NUMBER='(0,D8,0)';
      BIDIRECTIONAL='TRUE';
      INPUT_LOAD='(-0.01,0.01)';
      OUTPUT_LOAD='(1.0,-1.0)';
    'PT17D':
      PIN_NUMBER='(0,E9,0)';
      BIDIRECTIONAL='TRUE';
      INPUT_LOAD='(-0.01,0.01)';
      OUTPUT_LOAD='(1.0,-1.0)';
    'PT18A':
      PIN_NUMBER='(0,F8,0)';
      BIDIRECTIONAL='TRUE';
      INPUT_LOAD='(-0.01,0.01)';
      OUTPUT_LOAD='(1.0,-1.0)';
    'PT18B':
      PIN_NUMBER='(0,D9,0)';
      BIDIRECTIONAL='TRUE';
      INPUT_LOAD='(-0.01,0.01)';
      OUTPUT_LOAD='(1.0,-1.0)';
    'PT18C_SCL_PCLKT0_0':
      PIN_NUMBER='(0,A9,0)';
      BIDIRECTIONAL='TRUE';
      INPUT_LOAD='(-0.01,0.01)';
      OUTPUT_LOAD='(1.0,-1.0)';
    'PT18D_SDA_PCLKC0_0':
      PIN_NUMBER='(0,C9,0)';
      BIDIRECTIONAL='TRUE';
      INPUT_LOAD='(-0.01,0.01)';
      OUTPUT_LOAD='(1.0,-1.0)';
    'PT19A':
      PIN_NUMBER='(0,B9,0)';
      BIDIRECTIONAL='TRUE';
      INPUT_LOAD='(-0.01,0.01)';
      OUTPUT_LOAD='(1.0,-1.0)';
    'PT19B':
      PIN_NUMBER='(0,A10,0)';
      BIDIRECTIONAL='TRUE';
      INPUT_LOAD='(-0.01,0.01)';
      OUTPUT_LOAD='(1.0,-1.0)';
    'PT19C':
      PIN_NUMBER='(0,F9,0)';
      BIDIRECTIONAL='TRUE';
      INPUT_LOAD='(-0.01,0.01)';
      OUTPUT_LOAD='(1.0,-1.0)';
    'PT19D':
      PIN_NUMBER='(0,E11,0)';
      BIDIRECTIONAL='TRUE';
      INPUT_LOAD='(-0.01,0.01)';
      OUTPUT_LOAD='(1.0,-1.0)';
    'PT20A':
      PIN_NUMBER='(0,D10,0)';
      BIDIRECTIONAL='TRUE';
      INPUT_LOAD='(-0.01,0.01)';
      OUTPUT_LOAD='(1.0,-1.0)';
    'PT20B':
      PIN_NUMBER='(0,E10,0)';
      BIDIRECTIONAL='TRUE';
      INPUT_LOAD='(-0.01,0.01)';
      OUTPUT_LOAD='(1.0,-1.0)';
    'PT20C_JTAGENB':
      PIN_NUMBER='(0,C10,0)';
      BIDIRECTIONAL='TRUE';
      INPUT_LOAD='(-0.01,0.01)';
      OUTPUT_LOAD='(1.0,-1.0)';
    'PT20D_PROGRAMN':
      PIN_NUMBER='(0,B10,0)';
      BIDIRECTIONAL='TRUE';
      INPUT_LOAD='(-0.01,0.01)';
      OUTPUT_LOAD='(1.0,-1.0)';
    'PT21A':
      PIN_NUMBER='(0,A11,0)';
      BIDIRECTIONAL='TRUE';
      INPUT_LOAD='(-0.01,0.01)';
      OUTPUT_LOAD='(1.0,-1.0)';
    'PT21B':
      PIN_NUMBER='(0,C11,0)';
      BIDIRECTIONAL='TRUE';
      INPUT_LOAD='(-0.01,0.01)';
      OUTPUT_LOAD='(1.0,-1.0)';
    'PT21C':
      PIN_NUMBER='(0,F10,0)';
      BIDIRECTIONAL='TRUE';
      INPUT_LOAD='(-0.01,0.01)';
      OUTPUT_LOAD='(1.0,-1.0)';
    'PT21D':
      PIN_NUMBER='(0,D11,0)';
      BIDIRECTIONAL='TRUE';
      INPUT_LOAD='(-0.01,0.01)';
      OUTPUT_LOAD='(1.0,-1.0)';
    'PT22A':
      PIN_NUMBER='(0,B11,0)';
      BIDIRECTIONAL='TRUE';
      INPUT_LOAD='(-0.01,0.01)';
      OUTPUT_LOAD='(1.0,-1.0)';
    'PT22B':
      PIN_NUMBER='(0,A12,0)';
      BIDIRECTIONAL='TRUE';
      INPUT_LOAD='(-0.01,0.01)';
      OUTPUT_LOAD='(1.0,-1.0)';
    'PT22C':
      PIN_NUMBER='(0,B13,0)';
      BIDIRECTIONAL='TRUE';
      INPUT_LOAD='(-0.01,0.01)';
      OUTPUT_LOAD='(1.0,-1.0)';
    'PT22D':
      PIN_NUMBER='(0,A14,0)';
      BIDIRECTIONAL='TRUE';
      INPUT_LOAD='(-0.01,0.01)';
      OUTPUT_LOAD='(1.0,-1.0)';
    'PT23A':
      PIN_NUMBER='(0,C12,0)';
      BIDIRECTIONAL='TRUE';
      INPUT_LOAD='(-0.01,0.01)';
      OUTPUT_LOAD='(1.0,-1.0)';
    'PT23B':
      PIN_NUMBER='(0,B12,0)';
      BIDIRECTIONAL='TRUE';
      INPUT_LOAD='(-0.01,0.01)';
      OUTPUT_LOAD='(1.0,-1.0)';
    'PT24A':
      PIN_NUMBER='(0,B14,0)';
      BIDIRECTIONAL='TRUE';
      INPUT_LOAD='(-0.01,0.01)';
      OUTPUT_LOAD='(1.0,-1.0)';
    'PT24B':
      PIN_NUMBER='(0,A15,0)';
      BIDIRECTIONAL='TRUE';
      INPUT_LOAD='(-0.01,0.01)';
      OUTPUT_LOAD='(1.0,-1.0)';
    'PT24C_INITN':
      PIN_NUMBER='(0,A13,0)';
      BIDIRECTIONAL='TRUE';
      INPUT_LOAD='(-0.01,0.01)';
      OUTPUT_LOAD='(1.0,-1.0)';
    'PT24D_DONE':
      PIN_NUMBER='(0,C13,0)';
      BIDIRECTIONAL='TRUE';
      INPUT_LOAD='(-0.01,0.01)';
      OUTPUT_LOAD='(1.0,-1.0)';
    'GND'<0>:
      PIN_NUMBER='(0,0,B2)';
      PINUSE='GROUND';
      NO_LOAD_CHECK='Both';
      NO_IO_CHECK='Both';
      NO_ASSERT_CHECK='TRUE';
      NO_DIR_CHECK='TRUE';
      ALLOW_CONNECT='TRUE';
    'GND'<1>:
      PIN_NUMBER='(0,0,B15)';
      PINUSE='GROUND';
      NO_LOAD_CHECK='Both';
      NO_IO_CHECK='Both';
      NO_ASSERT_CHECK='TRUE';
      NO_DIR_CHECK='TRUE';
      ALLOW_CONNECT='TRUE';
    'GND'<2>:
      PIN_NUMBER='(0,0,C3)';
      PINUSE='GROUND';
      NO_LOAD_CHECK='Both';
      NO_IO_CHECK='Both';
      NO_ASSERT_CHECK='TRUE';
      NO_DIR_CHECK='TRUE';
      ALLOW_CONNECT='TRUE';
    'GND'<3>:
      PIN_NUMBER='(0,0,C14)';
      PINUSE='GROUND';
      NO_LOAD_CHECK='Both';
      NO_IO_CHECK='Both';
      NO_ASSERT_CHECK='TRUE';
      NO_DIR_CHECK='TRUE';
      ALLOW_CONNECT='TRUE';
    'GND'<4>:
      PIN_NUMBER='(0,0,D4)';
      PINUSE='GROUND';
      NO_LOAD_CHECK='Both';
      NO_IO_CHECK='Both';
      NO_ASSERT_CHECK='TRUE';
      NO_DIR_CHECK='TRUE';
      ALLOW_CONNECT='TRUE';
    'GND'<5>:
      PIN_NUMBER='(0,0,D13)';
      PINUSE='GROUND';
      NO_LOAD_CHECK='Both';
      NO_IO_CHECK='Both';
      NO_ASSERT_CHECK='TRUE';
      NO_DIR_CHECK='TRUE';
      ALLOW_CONNECT='TRUE';
    'GND'<6>:
      PIN_NUMBER='(0,0,E5)';
      PINUSE='GROUND';
      NO_LOAD_CHECK='Both';
      NO_IO_CHECK='Both';
      NO_ASSERT_CHECK='TRUE';
      NO_DIR_CHECK='TRUE';
      ALLOW_CONNECT='TRUE';
    'GND'<7>:
      PIN_NUMBER='(0,0,E12)';
      PINUSE='GROUND';
      NO_LOAD_CHECK='Both';
      NO_IO_CHECK='Both';
      NO_ASSERT_CHECK='TRUE';
      NO_DIR_CHECK='TRUE';
      ALLOW_CONNECT='TRUE';
    'GND'<8>:
      PIN_NUMBER='(0,0,F6)';
      PINUSE='GROUND';
      NO_LOAD_CHECK='Both';
      NO_IO_CHECK='Both';
      NO_ASSERT_CHECK='TRUE';
      NO_DIR_CHECK='TRUE';
      ALLOW_CONNECT='TRUE';
    'GND'<9>:
      PIN_NUMBER='(0,0,F11)';
      PINUSE='GROUND';
      NO_LOAD_CHECK='Both';
      NO_IO_CHECK='Both';
      NO_ASSERT_CHECK='TRUE';
      NO_DIR_CHECK='TRUE';
      ALLOW_CONNECT='TRUE';
    'GND'<10>:
      PIN_NUMBER='(0,0,H8)';
      PINUSE='GROUND';
      NO_LOAD_CHECK='Both';
      NO_IO_CHECK='Both';
      NO_ASSERT_CHECK='TRUE';
      NO_DIR_CHECK='TRUE';
      ALLOW_CONNECT='TRUE';
    'GND'<11>:
      PIN_NUMBER='(0,0,H9)';
      PINUSE='GROUND';
      NO_LOAD_CHECK='Both';
      NO_IO_CHECK='Both';
      NO_ASSERT_CHECK='TRUE';
      NO_DIR_CHECK='TRUE';
      ALLOW_CONNECT='TRUE';
    'GND'<12>:
      PIN_NUMBER='(0,0,J8)';
      PINUSE='GROUND';
      NO_LOAD_CHECK='Both';
      NO_IO_CHECK='Both';
      NO_ASSERT_CHECK='TRUE';
      NO_DIR_CHECK='TRUE';
      ALLOW_CONNECT='TRUE';
    'GND'<13>:
      PIN_NUMBER='(0,0,J9)';
      PINUSE='GROUND';
      NO_LOAD_CHECK='Both';
      NO_IO_CHECK='Both';
      NO_ASSERT_CHECK='TRUE';
      NO_DIR_CHECK='TRUE';
      ALLOW_CONNECT='TRUE';
    'GND'<14>:
      PIN_NUMBER='(0,0,L6)';
      PINUSE='GROUND';
      NO_LOAD_CHECK='Both';
      NO_IO_CHECK='Both';
      NO_ASSERT_CHECK='TRUE';
      NO_DIR_CHECK='TRUE';
      ALLOW_CONNECT='TRUE';
    'GND'<15>:
      PIN_NUMBER='(0,0,L11)';
      PINUSE='GROUND';
      NO_LOAD_CHECK='Both';
      NO_IO_CHECK='Both';
      NO_ASSERT_CHECK='TRUE';
      NO_DIR_CHECK='TRUE';
      ALLOW_CONNECT='TRUE';
    'GND'<16>:
      PIN_NUMBER='(0,0,M5)';
      PINUSE='GROUND';
      NO_LOAD_CHECK='Both';
      NO_IO_CHECK='Both';
      NO_ASSERT_CHECK='TRUE';
      NO_DIR_CHECK='TRUE';
      ALLOW_CONNECT='TRUE';
    'GND'<17>:
      PIN_NUMBER='(0,0,M12)';
      PINUSE='GROUND';
      NO_LOAD_CHECK='Both';
      NO_IO_CHECK='Both';
      NO_ASSERT_CHECK='TRUE';
      NO_DIR_CHECK='TRUE';
      ALLOW_CONNECT='TRUE';
    'GND'<18>:
      PIN_NUMBER='(0,0,N4)';
      PINUSE='GROUND';
      NO_LOAD_CHECK='Both';
      NO_IO_CHECK='Both';
      NO_ASSERT_CHECK='TRUE';
      NO_DIR_CHECK='TRUE';
      ALLOW_CONNECT='TRUE';
    'GND'<19>:
      PIN_NUMBER='(0,0,N13)';
      PINUSE='GROUND';
      NO_LOAD_CHECK='Both';
      NO_IO_CHECK='Both';
      NO_ASSERT_CHECK='TRUE';
      NO_DIR_CHECK='TRUE';
      ALLOW_CONNECT='TRUE';
    'GND'<20>:
      PIN_NUMBER='(0,0,P3)';
      PINUSE='GROUND';
      NO_LOAD_CHECK='Both';
      NO_IO_CHECK='Both';
      NO_ASSERT_CHECK='TRUE';
      NO_DIR_CHECK='TRUE';
      ALLOW_CONNECT='TRUE';
    'GND'<21>:
      PIN_NUMBER='(0,0,P14)';
      PINUSE='GROUND';
      NO_LOAD_CHECK='Both';
      NO_IO_CHECK='Both';
      NO_ASSERT_CHECK='TRUE';
      NO_DIR_CHECK='TRUE';
      ALLOW_CONNECT='TRUE';
    'GND'<22>:
      PIN_NUMBER='(0,0,R2)';
      PINUSE='GROUND';
      NO_LOAD_CHECK='Both';
      NO_IO_CHECK='Both';
      NO_ASSERT_CHECK='TRUE';
      NO_DIR_CHECK='TRUE';
      ALLOW_CONNECT='TRUE';
    'GND'<23>:
      PIN_NUMBER='(0,0,R15)';
      PINUSE='GROUND';
      NO_LOAD_CHECK='Both';
      NO_IO_CHECK='Both';
      NO_ASSERT_CHECK='TRUE';
      NO_DIR_CHECK='TRUE';
      ALLOW_CONNECT='TRUE';
    'VCC'<0>:
      PIN_NUMBER='(0,0,A1)';
      PINUSE='POWER';
      NO_LOAD_CHECK='Both';
      NO_IO_CHECK='Both';
      NO_ASSERT_CHECK='TRUE';
      NO_DIR_CHECK='TRUE';
      ALLOW_CONNECT='TRUE';
    'VCC'<1>:
      PIN_NUMBER='(0,0,A16)';
      PINUSE='POWER';
      NO_LOAD_CHECK='Both';
      NO_IO_CHECK='Both';
      NO_ASSERT_CHECK='TRUE';
      NO_DIR_CHECK='TRUE';
      ALLOW_CONNECT='TRUE';
    'VCC'<2>:
      PIN_NUMBER='(0,0,T1)';
      PINUSE='POWER';
      NO_LOAD_CHECK='Both';
      NO_IO_CHECK='Both';
      NO_ASSERT_CHECK='TRUE';
      NO_DIR_CHECK='TRUE';
      ALLOW_CONNECT='TRUE';
    'VCC'<3>:
      PIN_NUMBER='(0,0,T16)';
      PINUSE='POWER';
      NO_LOAD_CHECK='Both';
      NO_IO_CHECK='Both';
      NO_ASSERT_CHECK='TRUE';
      NO_DIR_CHECK='TRUE';
      ALLOW_CONNECT='TRUE';
    'VCC'<4>:
      PIN_NUMBER='(0,0,G7)';
      PINUSE='POWER';
      NO_LOAD_CHECK='Both';
      NO_IO_CHECK='Both';
      NO_ASSERT_CHECK='TRUE';
      NO_DIR_CHECK='TRUE';
      ALLOW_CONNECT='TRUE';
    'VCC'<5>:
      PIN_NUMBER='(0,0,G10)';
      PINUSE='POWER';
      NO_LOAD_CHECK='Both';
      NO_IO_CHECK='Both';
      NO_ASSERT_CHECK='TRUE';
      NO_DIR_CHECK='TRUE';
      ALLOW_CONNECT='TRUE';
    'VCC'<6>:
      PIN_NUMBER='(0,0,K7)';
      PINUSE='POWER';
      NO_LOAD_CHECK='Both';
      NO_IO_CHECK='Both';
      NO_ASSERT_CHECK='TRUE';
      NO_DIR_CHECK='TRUE';
      ALLOW_CONNECT='TRUE';
    'VCC'<7>:
      PIN_NUMBER='(0,0,K10)';
      PINUSE='POWER';
      NO_LOAD_CHECK='Both';
      NO_IO_CHECK='Both';
      NO_ASSERT_CHECK='TRUE';
      NO_DIR_CHECK='TRUE';
      ALLOW_CONNECT='TRUE';
    'VCCIO0'<0>:
      PIN_NUMBER='(0,0,G8)';
      PINUSE='POWER';
      NO_LOAD_CHECK='Both';
      NO_IO_CHECK='Both';
      NO_ASSERT_CHECK='TRUE';
      NO_DIR_CHECK='TRUE';
      ALLOW_CONNECT='TRUE';
    'VCCIO0'<1>:
      PIN_NUMBER='(0,0,D12)';
      PINUSE='POWER';
      NO_LOAD_CHECK='Both';
      NO_IO_CHECK='Both';
      NO_ASSERT_CHECK='TRUE';
      NO_DIR_CHECK='TRUE';
      ALLOW_CONNECT='TRUE';
    'VCCIO0'<2>:
      PIN_NUMBER='(0,0,G9)';
      PINUSE='POWER';
      NO_LOAD_CHECK='Both';
      NO_IO_CHECK='Both';
      NO_ASSERT_CHECK='TRUE';
      NO_DIR_CHECK='TRUE';
      ALLOW_CONNECT='TRUE';
    'VCCIO1'<0>:
      PIN_NUMBER='(0,0,E13)';
      PINUSE='POWER';
      NO_LOAD_CHECK='Both';
      NO_IO_CHECK='Both';
      NO_ASSERT_CHECK='TRUE';
      NO_DIR_CHECK='TRUE';
      ALLOW_CONNECT='TRUE';
    'VCCIO1'<1>:
      PIN_NUMBER='(0,0,H10)';
      PINUSE='POWER';
      NO_LOAD_CHECK='Both';
      NO_IO_CHECK='Both';
      NO_ASSERT_CHECK='TRUE';
      NO_DIR_CHECK='TRUE';
      ALLOW_CONNECT='TRUE';
    'VCCIO1'<2>:
      PIN_NUMBER='(0,0,J10)';
      PINUSE='POWER';
      NO_LOAD_CHECK='Both';
      NO_IO_CHECK='Both';
      NO_ASSERT_CHECK='TRUE';
      NO_DIR_CHECK='TRUE';
      ALLOW_CONNECT='TRUE';
    'VCCIO1'<3>:
      PIN_NUMBER='(0,0,M13)';
      PINUSE='POWER';
      NO_LOAD_CHECK='Both';
      NO_IO_CHECK='Both';
      NO_ASSERT_CHECK='TRUE';
      NO_DIR_CHECK='TRUE';
      ALLOW_CONNECT='TRUE';
    'VCCIO2'<0>:
      PIN_NUMBER='(0,0,K9)';
      PINUSE='POWER';
      NO_LOAD_CHECK='Both';
      NO_IO_CHECK='Both';
      NO_ASSERT_CHECK='TRUE';
      NO_DIR_CHECK='TRUE';
      ALLOW_CONNECT='TRUE';
    'VCCIO2'<1>:
      PIN_NUMBER='(0,0,N12)';
      PINUSE='POWER';
      NO_LOAD_CHECK='Both';
      NO_IO_CHECK='Both';
      NO_ASSERT_CHECK='TRUE';
      NO_DIR_CHECK='TRUE';
      ALLOW_CONNECT='TRUE';
    'VCCIO2'<2>:
      PIN_NUMBER='(0,0,K8)';
      PINUSE='POWER';
      NO_LOAD_CHECK='Both';
      NO_IO_CHECK='Both';
      NO_ASSERT_CHECK='TRUE';
      NO_DIR_CHECK='TRUE';
      ALLOW_CONNECT='TRUE';
    'VCCIO2'<3>:
      PIN_NUMBER='(0,0,N5)';
      PINUSE='POWER';
      NO_LOAD_CHECK='Both';
      NO_IO_CHECK='Both';
      NO_ASSERT_CHECK='TRUE';
      NO_DIR_CHECK='TRUE';
      ALLOW_CONNECT='TRUE';
    'VCCIO4'<0>:
      PIN_NUMBER='(0,0,J7)';
      PINUSE='POWER';
      NO_LOAD_CHECK='Both';
      NO_IO_CHECK='Both';
      NO_ASSERT_CHECK='TRUE';
      NO_DIR_CHECK='TRUE';
      ALLOW_CONNECT='TRUE';
    'VCCIO4'<1>:
      PIN_NUMBER='(0,0,H7)';
      PINUSE='POWER';
      NO_LOAD_CHECK='Both';
      NO_IO_CHECK='Both';
      NO_ASSERT_CHECK='TRUE';
      NO_DIR_CHECK='TRUE';
      ALLOW_CONNECT='TRUE';
    'VCCIO5'<0>:
      PIN_NUMBER='(0,0,E4)';
      PINUSE='POWER';
      NO_LOAD_CHECK='Both';
      NO_IO_CHECK='Both';
      NO_ASSERT_CHECK='TRUE';
      NO_DIR_CHECK='TRUE';
      ALLOW_CONNECT='TRUE';
    'VCCIO0'<3>:
      PIN_NUMBER='(0,0,D5)';
      PINUSE='POWER';
      NO_LOAD_CHECK='Both';
      NO_IO_CHECK='Both';
      NO_ASSERT_CHECK='TRUE';
      NO_DIR_CHECK='TRUE';
      ALLOW_CONNECT='TRUE';
    'NC'<0>:
      PIN_NUMBER='(0,0,A2)';
      PINUSE='NC';
      NO_LOAD_CHECK='Both';
      NO_IO_CHECK='Both';
      NO_ASSERT_CHECK='TRUE';
      NO_DIR_CHECK='TRUE';
      ALLOW_CONNECT='TRUE';
    'VCCIO3'<0>:
      PIN_NUMBER='(0,0,M4)';
      PINUSE='POWER';
      NO_LOAD_CHECK='Both';
      NO_IO_CHECK='Both';
      NO_ASSERT_CHECK='TRUE';
      NO_DIR_CHECK='TRUE';
      ALLOW_CONNECT='TRUE';
  end_pin;
  body
    PART_NAME='LCMXO2_A';
    PHYS_DES_PREFIX='U';
  end_body;
end_primitive;
primitive 'LCMXO2_A_484BGA';
  pin
    'PB3B':
      PIN_NUMBER='(AA3,0,0,0,0,0,0)';
      BIDIRECTIONAL='TRUE';
      INPUT_LOAD='(-0.01,0.01)';
      OUTPUT_LOAD='(1.0,-1.0)';
    'PB7A':
      PIN_NUMBER='(AA4,0,0,0,0,0,0)';
      BIDIRECTIONAL='TRUE';
      INPUT_LOAD='(-0.01,0.01)';
      OUTPUT_LOAD='(1.0,-1.0)';
    'PB10A':
      PIN_NUMBER='(AA7,0,0,0,0,0,0)';
      BIDIRECTIONAL='TRUE';
      INPUT_LOAD='(-0.01,0.01)';
      OUTPUT_LOAD='(1.0,-1.0)';
    'PB12D':
      PIN_NUMBER='(AA8,0,0,0,0,0,0)';
      BIDIRECTIONAL='TRUE';
      INPUT_LOAD='(-0.01,0.01)';
      OUTPUT_LOAD='(1.0,-1.0)';
    'PB13A_PCLKT2_0':
      PIN_NUMBER='(AA9,0,0,0,0,0,0)';
      BIDIRECTIONAL='TRUE';
      INPUT_LOAD='(-0.01,0.01)';
      OUTPUT_LOAD='(1.0,-1.0)';
    'PB15A':
      PIN_NUMBER='(AA10,0,0,0,0,0,0)';
      BIDIRECTIONAL='TRUE';
      INPUT_LOAD='(-0.01,0.01)';
      OUTPUT_LOAD='(1.0,-1.0)';
    'PB15C':
      PIN_NUMBER='(AA11,0,0,0,0,0,0)';
      BIDIRECTIONAL='TRUE';
      INPUT_LOAD='(-0.01,0.01)';
      OUTPUT_LOAD='(1.0,-1.0)';
    'PB18B':
      PIN_NUMBER='(AA12,0,0,0,0,0,0)';
      BIDIRECTIONAL='TRUE';
      INPUT_LOAD='(-0.01,0.01)';
      OUTPUT_LOAD='(1.0,-1.0)';
    'PB18D':
      PIN_NUMBER='(AA13,0,0,0,0,0,0)';
      BIDIRECTIONAL='TRUE';
      INPUT_LOAD='(-0.01,0.01)';
      OUTPUT_LOAD='(1.0,-1.0)';
    'PB20B_PCLKC2_1':
      PIN_NUMBER='(AA14,0,0,0,0,0,0)';
      BIDIRECTIONAL='TRUE';
      INPUT_LOAD='(-0.01,0.01)';
      OUTPUT_LOAD='(1.0,-1.0)';
    'PB23B':
      PIN_NUMBER='(AA16,0,0,0,0,0,0)';
      BIDIRECTIONAL='TRUE';
      INPUT_LOAD='(-0.01,0.01)';
      OUTPUT_LOAD='(1.0,-1.0)';
    'PB30A_SN':
      PIN_NUMBER='(AA20,0,0,0,0,0,0)';
      BIDIRECTIONAL='TRUE';
      INPUT_LOAD='(-0.01,0.01)';
      OUTPUT_LOAD='(1.0,-1.0)';
    'PB6C':
      PIN_NUMBER='(AB2,0,0,0,0,0,0)';
      BIDIRECTIONAL='TRUE';
      INPUT_LOAD='(-0.01,0.01)';
      OUTPUT_LOAD='(1.0,-1.0)';
    'PB6D':
      PIN_NUMBER='(AB3,0,0,0,0,0,0)';
      BIDIRECTIONAL='TRUE';
      INPUT_LOAD='(-0.01,0.01)';
      OUTPUT_LOAD='(1.0,-1.0)';
    'PB9A_MCLK_CCLK':
      PIN_NUMBER='(AB6,0,0,0,0,0,0)';
      BIDIRECTIONAL='TRUE';
      INPUT_LOAD='(-0.01,0.01)';
      OUTPUT_LOAD='(1.0,-1.0)';
    'PB10B':
      PIN_NUMBER='(AB7,0,0,0,0,0,0)';
      BIDIRECTIONAL='TRUE';
      INPUT_LOAD='(-0.01,0.01)';
      OUTPUT_LOAD='(1.0,-1.0)';
    'PB15B':
      PIN_NUMBER='(AB10,0,0,0,0,0,0)';
      BIDIRECTIONAL='TRUE';
      INPUT_LOAD='(-0.01,0.01)';
      OUTPUT_LOAD='(1.0,-1.0)';
    'PB15D':
      PIN_NUMBER='(AB11,0,0,0,0,0,0)';
      BIDIRECTIONAL='TRUE';
      INPUT_LOAD='(-0.01,0.01)';
      OUTPUT_LOAD='(1.0,-1.0)';
    'PB18A':
      PIN_NUMBER='(AB12,0,0,0,0,0,0)';
      BIDIRECTIONAL='TRUE';
      INPUT_LOAD='(-0.01,0.01)';
      OUTPUT_LOAD='(1.0,-1.0)';
    'PB18C':
      PIN_NUMBER='(AB13,0,0,0,0,0,0)';
      BIDIRECTIONAL='TRUE';
      INPUT_LOAD='(-0.01,0.01)';
      OUTPUT_LOAD='(1.0,-1.0)';
    'PB21B':
      PIN_NUMBER='(AB15,0,0,0,0,0,0)';
      BIDIRECTIONAL='TRUE';
      INPUT_LOAD='(-0.01,0.01)';
      OUTPUT_LOAD='(1.0,-1.0)';
    'PB23A':
      PIN_NUMBER='(AB16,0,0,0,0,0,0)';
      BIDIRECTIONAL='TRUE';
      INPUT_LOAD='(-0.01,0.01)';
      OUTPUT_LOAD='(1.0,-1.0)';
    'PB24B':
      PIN_NUMBER='(AB17,0,0,0,0,0,0)';
      BIDIRECTIONAL='TRUE';
      INPUT_LOAD='(-0.01,0.01)';
      OUTPUT_LOAD='(1.0,-1.0)';
    'PB26D':
      PIN_NUMBER='(AB18,0,0,0,0,0,0)';
      BIDIRECTIONAL='TRUE';
      INPUT_LOAD='(-0.01,0.01)';
      OUTPUT_LOAD='(1.0,-1.0)';
    'PB27A':
      PIN_NUMBER='(AB20,0,0,0,0,0,0)';
      BIDIRECTIONAL='TRUE';
      INPUT_LOAD='(-0.01,0.01)';
      OUTPUT_LOAD='(1.0,-1.0)';
    'PB27B':
      PIN_NUMBER='(AB21,0,0,0,0,0,0)';
      BIDIRECTIONAL='TRUE';
      INPUT_LOAD='(-0.01,0.01)';
      OUTPUT_LOAD='(1.0,-1.0)';
    'PB4D':
      PIN_NUMBER='(T8,0,0,0,0,0,0)';
      BIDIRECTIONAL='TRUE';
      INPUT_LOAD='(-0.01,0.01)';
      OUTPUT_LOAD='(1.0,-1.0)';
    'PB10D':
      PIN_NUMBER='(T10,0,0,0,0,0,0)';
      BIDIRECTIONAL='TRUE';
      INPUT_LOAD='(-0.01,0.01)';
      OUTPUT_LOAD='(1.0,-1.0)';
    'PB13D':
      PIN_NUMBER='(T11,0,0,0,0,0,0)';
      BIDIRECTIONAL='TRUE';
      INPUT_LOAD='(-0.01,0.01)';
      OUTPUT_LOAD='(1.0,-1.0)';
    'PB20C':
      PIN_NUMBER='(T12,0,0,0,0,0,0)';
      BIDIRECTIONAL='TRUE';
      INPUT_LOAD='(-0.01,0.01)';
      OUTPUT_LOAD='(1.0,-1.0)';
    'PB29C':
      PIN_NUMBER='(T15,0,0,0,0,0,0)';
      BIDIRECTIONAL='TRUE';
      INPUT_LOAD='(-0.01,0.01)';
      OUTPUT_LOAD='(1.0,-1.0)';
    'PB30D':
      PIN_NUMBER='(T16,0,0,0,0,0,0)';
      BIDIRECTIONAL='TRUE';
      INPUT_LOAD='(-0.01,0.01)';
      OUTPUT_LOAD='(1.0,-1.0)';
    'PB3C':
      PIN_NUMBER='(U6,0,0,0,0,0,0)';
      BIDIRECTIONAL='TRUE';
      INPUT_LOAD='(-0.01,0.01)';
      OUTPUT_LOAD='(1.0,-1.0)';
    'PB4C':
      PIN_NUMBER='(U7,0,0,0,0,0,0)';
      BIDIRECTIONAL='TRUE';
      INPUT_LOAD='(-0.01,0.01)';
      OUTPUT_LOAD='(1.0,-1.0)';
    'PB6A':
      PIN_NUMBER='(U8,0,0,0,0,0,0)';
      BIDIRECTIONAL='TRUE';
      INPUT_LOAD='(-0.01,0.01)';
      OUTPUT_LOAD='(1.0,-1.0)';
    'PB10C':
      PIN_NUMBER='(U10,0,0,0,0,0,0)';
      BIDIRECTIONAL='TRUE';
      INPUT_LOAD='(-0.01,0.01)';
      OUTPUT_LOAD='(1.0,-1.0)';
    'PB13C':
      PIN_NUMBER='(U11,0,0,0,0,0,0)';
      BIDIRECTIONAL='TRUE';
      INPUT_LOAD='(-0.01,0.01)';
      OUTPUT_LOAD='(1.0,-1.0)';
    'PB20D':
      PIN_NUMBER='(U12,0,0,0,0,0,0)';
      BIDIRECTIONAL='TRUE';
      INPUT_LOAD='(-0.01,0.01)';
      OUTPUT_LOAD='(1.0,-1.0)';
    'PB27D':
      PIN_NUMBER='(U15,0,0,0,0,0,0)';
      BIDIRECTIONAL='TRUE';
      INPUT_LOAD='(-0.01,0.01)';
      OUTPUT_LOAD='(1.0,-1.0)';
    'PB29D':
      PIN_NUMBER='(U16,0,0,0,0,0,0)';
      BIDIRECTIONAL='TRUE';
      INPUT_LOAD='(-0.01,0.01)';
      OUTPUT_LOAD='(1.0,-1.0)';
    'PB3D':
      PIN_NUMBER='(V6,0,0,0,0,0,0)';
      BIDIRECTIONAL='TRUE';
      INPUT_LOAD='(-0.01,0.01)';
      OUTPUT_LOAD='(1.0,-1.0)';
    'PB6B':
      PIN_NUMBER='(V7,0,0,0,0,0,0)';
      BIDIRECTIONAL='TRUE';
      INPUT_LOAD='(-0.01,0.01)';
      OUTPUT_LOAD='(1.0,-1.0)';
    'PB9C':
      PIN_NUMBER='(V8,0,0,0,0,0,0)';
      BIDIRECTIONAL='TRUE';
      INPUT_LOAD='(-0.01,0.01)';
      OUTPUT_LOAD='(1.0,-1.0)';
    'PB12A':
      PIN_NUMBER='(V11,0,0,0,0,0,0)';
      BIDIRECTIONAL='TRUE';
      INPUT_LOAD='(-0.01,0.01)';
      OUTPUT_LOAD='(1.0,-1.0)';
    'PB21D':
      PIN_NUMBER='(V12,0,0,0,0,0,0)';
      BIDIRECTIONAL='TRUE';
      INPUT_LOAD='(-0.01,0.01)';
      OUTPUT_LOAD='(1.0,-1.0)';
    'PB23D':
      PIN_NUMBER='(V13,0,0,0,0,0,0)';
      BIDIRECTIONAL='TRUE';
      INPUT_LOAD='(-0.01,0.01)';
      OUTPUT_LOAD='(1.0,-1.0)';
    'PB24D':
      PIN_NUMBER='(V14,0,0,0,0,0,0)';
      BIDIRECTIONAL='TRUE';
      INPUT_LOAD='(-0.01,0.01)';
      OUTPUT_LOAD='(1.0,-1.0)';
    'PB27C':
      PIN_NUMBER='(V16,0,0,0,0,0,0)';
      BIDIRECTIONAL='TRUE';
      INPUT_LOAD='(-0.01,0.01)';
      OUTPUT_LOAD='(1.0,-1.0)';
    'PB30C':
      PIN_NUMBER='(V17,0,0,0,0,0,0)';
      BIDIRECTIONAL='TRUE';
      INPUT_LOAD='(-0.01,0.01)';
      OUTPUT_LOAD='(1.0,-1.0)';
    'PB4A_CSSPIN':
      PIN_NUMBER='(W5,0,0,0,0,0,0)';
      BIDIRECTIONAL='TRUE';
      INPUT_LOAD='(-0.01,0.01)';
      OUTPUT_LOAD='(1.0,-1.0)';
    'PB7C':
      PIN_NUMBER='(W6,0,0,0,0,0,0)';
      BIDIRECTIONAL='TRUE';
      INPUT_LOAD='(-0.01,0.01)';
      OUTPUT_LOAD='(1.0,-1.0)';
    'PB7D':
      PIN_NUMBER='(W7,0,0,0,0,0,0)';
      BIDIRECTIONAL='TRUE';
      INPUT_LOAD='(-0.01,0.01)';
      OUTPUT_LOAD='(1.0,-1.0)';
    'PB9D':
      PIN_NUMBER='(W8,0,0,0,0,0,0)';
      BIDIRECTIONAL='TRUE';
      INPUT_LOAD='(-0.01,0.01)';
      OUTPUT_LOAD='(1.0,-1.0)';
    'PB12B':
      PIN_NUMBER='(W11,0,0,0,0,0,0)';
      BIDIRECTIONAL='TRUE';
      INPUT_LOAD='(-0.01,0.01)';
      OUTPUT_LOAD='(1.0,-1.0)';
    'PB21C':
      PIN_NUMBER='(W12,0,0,0,0,0,0)';
      BIDIRECTIONAL='TRUE';
      INPUT_LOAD='(-0.01,0.01)';
      OUTPUT_LOAD='(1.0,-1.0)';
    'PB24C':
      PIN_NUMBER='(W14,0,0,0,0,0,0)';
      BIDIRECTIONAL='TRUE';
      INPUT_LOAD='(-0.01,0.01)';
      OUTPUT_LOAD='(1.0,-1.0)';
    'PB26A':
      PIN_NUMBER='(W16,0,0,0,0,0,0)';
      BIDIRECTIONAL='TRUE';
      INPUT_LOAD='(-0.01,0.01)';
      OUTPUT_LOAD='(1.0,-1.0)';
    'PB26B':
      PIN_NUMBER='(W17,0,0,0,0,0,0)';
      BIDIRECTIONAL='TRUE';
      INPUT_LOAD='(-0.01,0.01)';
      OUTPUT_LOAD='(1.0,-1.0)';
    'PB29B':
      PIN_NUMBER='(W18,0,0,0,0,0,0)';
      BIDIRECTIONAL='TRUE';
      INPUT_LOAD='(-0.01,0.01)';
      OUTPUT_LOAD='(1.0,-1.0)';
    'PB30B_SI_SISPI':
      PIN_NUMBER='(W19,0,0,0,0,0,0)';
      BIDIRECTIONAL='TRUE';
      INPUT_LOAD='(-0.01,0.01)';
      OUTPUT_LOAD='(1.0,-1.0)';
    'PB3A':
      PIN_NUMBER='(Y3,0,0,0,0,0,0)';
      BIDIRECTIONAL='TRUE';
      INPUT_LOAD='(-0.01,0.01)';
      OUTPUT_LOAD='(1.0,-1.0)';
    'PB4B':
      PIN_NUMBER='(Y4,0,0,0,0,0,0)';
      BIDIRECTIONAL='TRUE';
      INPUT_LOAD='(-0.01,0.01)';
      OUTPUT_LOAD='(1.0,-1.0)';
    'PB7B':
      PIN_NUMBER='(Y5,0,0,0,0,0,0)';
      BIDIRECTIONAL='TRUE';
      INPUT_LOAD='(-0.01,0.01)';
      OUTPUT_LOAD='(1.0,-1.0)';
    'PB9B_SO_SPISO':
      PIN_NUMBER='(Y7,0,0,0,0,0,0)';
      BIDIRECTIONAL='TRUE';
      INPUT_LOAD='(-0.01,0.01)';
      OUTPUT_LOAD='(1.0,-1.0)';
    'PB12C':
      PIN_NUMBER='(Y8,0,0,0,0,0,0)';
      BIDIRECTIONAL='TRUE';
      INPUT_LOAD='(-0.01,0.01)';
      OUTPUT_LOAD='(1.0,-1.0)';
    'PB13B_PCLKC2_0':
      PIN_NUMBER='(Y10,0,0,0,0,0,0)';
      BIDIRECTIONAL='TRUE';
      INPUT_LOAD='(-0.01,0.01)';
      OUTPUT_LOAD='(1.0,-1.0)';
    'PB23C':
      PIN_NUMBER='(Y12,0,0,0,0,0,0)';
      BIDIRECTIONAL='TRUE';
      INPUT_LOAD='(-0.01,0.01)';
      OUTPUT_LOAD='(1.0,-1.0)';
    'PB20A_PCLKT2_1':
      PIN_NUMBER='(Y13,0,0,0,0,0,0)';
      BIDIRECTIONAL='TRUE';
      INPUT_LOAD='(-0.01,0.01)';
      OUTPUT_LOAD='(1.0,-1.0)';
    'PB21A':
      PIN_NUMBER='(Y14,0,0,0,0,0,0)';
      BIDIRECTIONAL='TRUE';
      INPUT_LOAD='(-0.01,0.01)';
      OUTPUT_LOAD='(1.0,-1.0)';
    'PB24A':
      PIN_NUMBER='(Y16,0,0,0,0,0,0)';
      BIDIRECTIONAL='TRUE';
      INPUT_LOAD='(-0.01,0.01)';
      OUTPUT_LOAD='(1.0,-1.0)';
    'PB26C':
      PIN_NUMBER='(Y17,0,0,0,0,0,0)';
      BIDIRECTIONAL='TRUE';
      INPUT_LOAD='(-0.01,0.01)';
      OUTPUT_LOAD='(1.0,-1.0)';
    'PB29A':
      PIN_NUMBER='(Y19,0,0,0,0,0,0)';
      BIDIRECTIONAL='TRUE';
      INPUT_LOAD='(-0.01,0.01)';
      OUTPUT_LOAD='(1.0,-1.0)';
    'PL20A':
      PIN_NUMBER='(0,Y2,0,0,0,0,0)';
      BIDIRECTIONAL='TRUE';
      INPUT_LOAD='(-0.01,0.01)';
      OUTPUT_LOAD='(1.0,-1.0)';
    'PL18A':
      PIN_NUMBER='(0,Y1,0,0,0,0,0)';
      BIDIRECTIONAL='TRUE';
      INPUT_LOAD='(-0.01,0.01)';
      OUTPUT_LOAD='(1.0,-1.0)';
    'PL20B':
      PIN_NUMBER='(0,W4,0,0,0,0,0)';
      BIDIRECTIONAL='TRUE';
      INPUT_LOAD='(-0.01,0.01)';
      OUTPUT_LOAD='(1.0,-1.0)';
    'PL19A':
      PIN_NUMBER='(0,W3,0,0,0,0,0)';
      BIDIRECTIONAL='TRUE';
      INPUT_LOAD='(-0.01,0.01)';
      OUTPUT_LOAD='(1.0,-1.0)';
    'PL17B_PCLKC3_0':
      PIN_NUMBER='(0,W2,0,0,0,0,0)';
      BIDIRECTIONAL='TRUE';
      INPUT_LOAD='(-0.01,0.01)';
      OUTPUT_LOAD='(1.0,-1.0)';
    'PL19B':
      PIN_NUMBER='(0,V4,0,0,0,0,0)';
      BIDIRECTIONAL='TRUE';
      INPUT_LOAD='(-0.01,0.01)';
      OUTPUT_LOAD='(1.0,-1.0)';
    'PL17A_PCLKT3_0':
      PIN_NUMBER='(0,V3,0,0,0,0,0)';
      BIDIRECTIONAL='TRUE';
      INPUT_LOAD='(-0.01,0.01)';
      OUTPUT_LOAD='(1.0,-1.0)';
    'PL16B':
      PIN_NUMBER='(0,V1,0,0,0,0,0)';
      BIDIRECTIONAL='TRUE';
      INPUT_LOAD='(-0.01,0.01)';
      OUTPUT_LOAD='(1.0,-1.0)';
    'PL20C':
      PIN_NUMBER='(0,U5,0,0,0,0,0)';
      BIDIRECTIONAL='TRUE';
      INPUT_LOAD='(-0.01,0.01)';
      OUTPUT_LOAD='(1.0,-1.0)';
    'PL16A':
      PIN_NUMBER='(0,U3,0,0,0,0,0)';
      BIDIRECTIONAL='TRUE';
      INPUT_LOAD='(-0.01,0.01)';
      OUTPUT_LOAD='(1.0,-1.0)';
    'PL20D':
      PIN_NUMBER='(0,T7,0,0,0,0,0)';
      BIDIRECTIONAL='TRUE';
      INPUT_LOAD='(-0.01,0.01)';
      OUTPUT_LOAD='(1.0,-1.0)';
    'PL19D':
      PIN_NUMBER='(0,T6,0,0,0,0,0)';
      BIDIRECTIONAL='TRUE';
      INPUT_LOAD='(-0.01,0.01)';
      OUTPUT_LOAD='(1.0,-1.0)';
    'PL18C':
      PIN_NUMBER='(0,T5,0,0,0,0,0)';
      BIDIRECTIONAL='TRUE';
      INPUT_LOAD='(-0.01,0.01)';
      OUTPUT_LOAD='(1.0,-1.0)';
    'PL19C':
      PIN_NUMBER='(0,R7,0,0,0,0,0)';
      BIDIRECTIONAL='TRUE';
      INPUT_LOAD='(-0.01,0.01)';
      OUTPUT_LOAD='(1.0,-1.0)';
    'PL18D':
      PIN_NUMBER='(0,R6,0,0,0,0,0)';
      BIDIRECTIONAL='TRUE';
      INPUT_LOAD='(-0.01,0.01)';
      OUTPUT_LOAD='(1.0,-1.0)';
    'PL15B':
      PIN_NUMBER='(0,R3,0,0,0,0,0)';
      BIDIRECTIONAL='TRUE';
      INPUT_LOAD='(-0.01,0.01)';
      OUTPUT_LOAD='(1.0,-1.0)';
    'PL15A':
      PIN_NUMBER='(0,R2,0,0,0,0,0)';
      BIDIRECTIONAL='TRUE';
      INPUT_LOAD='(-0.01,0.01)';
      OUTPUT_LOAD='(1.0,-1.0)';
    'PL14B':
      PIN_NUMBER='(0,R1,0,0,0,0,0)';
      BIDIRECTIONAL='TRUE';
      INPUT_LOAD='(-0.01,0.01)';
      OUTPUT_LOAD='(1.0,-1.0)';
    'PL17C':
      PIN_NUMBER='(0,P7,0,0,0,0,0)';
      BIDIRECTIONAL='TRUE';
      INPUT_LOAD='(-0.01,0.01)';
      OUTPUT_LOAD='(1.0,-1.0)';
    'PL17D':
      PIN_NUMBER='(0,P6,0,0,0,0,0)';
      BIDIRECTIONAL='TRUE';
      INPUT_LOAD='(-0.01,0.01)';
      OUTPUT_LOAD='(1.0,-1.0)';
    'PL14A':
      PIN_NUMBER='(0,P3,0,0,0,0,0)';
      BIDIRECTIONAL='TRUE';
      INPUT_LOAD='(-0.01,0.01)';
      OUTPUT_LOAD='(1.0,-1.0)';
    'PL16C':
      PIN_NUMBER='(0,N7,0,0,0,0,0)';
      BIDIRECTIONAL='TRUE';
      INPUT_LOAD='(-0.01,0.01)';
      OUTPUT_LOAD='(1.0,-1.0)';
    'PL16D':
      PIN_NUMBER='(0,N6,0,0,0,0,0)';
      BIDIRECTIONAL='TRUE';
      INPUT_LOAD='(-0.01,0.01)';
      OUTPUT_LOAD='(1.0,-1.0)';
    'PL15D':
      PIN_NUMBER='(0,N5,0,0,0,0,0)';
      BIDIRECTIONAL='TRUE';
      INPUT_LOAD='(-0.01,0.01)';
      OUTPUT_LOAD='(1.0,-1.0)';
    'PL13B':
      PIN_NUMBER='(0,N2,0,0,0,0,0)';
      BIDIRECTIONAL='TRUE';
      INPUT_LOAD='(-0.01,0.01)';
      OUTPUT_LOAD='(1.0,-1.0)';
    'PL13A':
      PIN_NUMBER='(0,N1,0,0,0,0,0)';
      BIDIRECTIONAL='TRUE';
      INPUT_LOAD='(-0.01,0.01)';
      OUTPUT_LOAD='(1.0,-1.0)';
    'PL14C':
      PIN_NUMBER='(0,M7,0,0,0,0,0)';
      BIDIRECTIONAL='TRUE';
      INPUT_LOAD='(-0.01,0.01)';
      OUTPUT_LOAD='(1.0,-1.0)';
    'PL14D':
      PIN_NUMBER='(0,M6,0,0,0,0,0)';
      BIDIRECTIONAL='TRUE';
      INPUT_LOAD='(-0.01,0.01)';
      OUTPUT_LOAD='(1.0,-1.0)';
    'PL15C':
      PIN_NUMBER='(0,M3,0,0,0,0,0)';
      BIDIRECTIONAL='TRUE';
      INPUT_LOAD='(-0.01,0.01)';
      OUTPUT_LOAD='(1.0,-1.0)';
    'PL13D':
      PIN_NUMBER='(0,M2,0,0,0,0,0)';
      BIDIRECTIONAL='TRUE';
      INPUT_LOAD='(-0.01,0.01)';
      OUTPUT_LOAD='(1.0,-1.0)';
    'PL13C':
      PIN_NUMBER='(0,M1,0,0,0,0,0)';
      BIDIRECTIONAL='TRUE';
      INPUT_LOAD='(-0.01,0.01)';
      OUTPUT_LOAD='(1.0,-1.0)';
    'PL9C':
      PIN_NUMBER='(0,L5,0,0,0,0,0)';
      BIDIRECTIONAL='TRUE';
      INPUT_LOAD='(-0.01,0.01)';
      OUTPUT_LOAD='(1.0,-1.0)';
    'PL9D':
      PIN_NUMBER='(0,L4,0,0,0,0,0)';
      BIDIRECTIONAL='TRUE';
      INPUT_LOAD='(-0.01,0.01)';
      OUTPUT_LOAD='(1.0,-1.0)';
    'PL8D':
      PIN_NUMBER='(0,L3,0,0,0,0,0)';
      BIDIRECTIONAL='TRUE';
      INPUT_LOAD='(-0.01,0.01)';
      OUTPUT_LOAD='(1.0,-1.0)';
    'PL8C':
      PIN_NUMBER='(0,K5,0,0,0,0,0)';
      BIDIRECTIONAL='TRUE';
      INPUT_LOAD='(-0.01,0.01)';
      OUTPUT_LOAD='(1.0,-1.0)';
    'PL10B':
      PIN_NUMBER='(0,K3,0,0,0,0,0)';
      BIDIRECTIONAL='TRUE';
      INPUT_LOAD='(-0.01,0.01)';
      OUTPUT_LOAD='(1.0,-1.0)';
    'PL10C_PCLKT4_0':
      PIN_NUMBER='(0,K2,0,0,0,0,0)';
      BIDIRECTIONAL='TRUE';
      INPUT_LOAD='(-0.01,0.01)';
      OUTPUT_LOAD='(1.0,-1.0)';
    'PL10D_PCLKC4_0':
      PIN_NUMBER='(0,K1,0,0,0,0,0)';
      BIDIRECTIONAL='TRUE';
      INPUT_LOAD='(-0.01,0.01)';
      OUTPUT_LOAD='(1.0,-1.0)';
    'PL7C':
      PIN_NUMBER='(0,J5,0,0,0,0,0)';
      BIDIRECTIONAL='TRUE';
      INPUT_LOAD='(-0.01,0.01)';
      OUTPUT_LOAD='(1.0,-1.0)';
    'PL7D':
      PIN_NUMBER='(0,J4,0,0,0,0,0)';
      BIDIRECTIONAL='TRUE';
      INPUT_LOAD='(-0.01,0.01)';
      OUTPUT_LOAD='(1.0,-1.0)';
    'PL9B':
      PIN_NUMBER='(0,J3,0,0,0,0,0)';
      BIDIRECTIONAL='TRUE';
      INPUT_LOAD='(-0.01,0.01)';
      OUTPUT_LOAD='(1.0,-1.0)';
    'PL10A':
      PIN_NUMBER='(0,J2,0,0,0,0,0)';
      BIDIRECTIONAL='TRUE';
      INPUT_LOAD='(-0.01,0.01)';
      OUTPUT_LOAD='(1.0,-1.0)';
    'PL3D':
      PIN_NUMBER='(0,H7,0,0,0,0,0)';
      BIDIRECTIONAL='TRUE';
      INPUT_LOAD='(-0.01,0.01)';
      OUTPUT_LOAD='(1.0,-1.0)';
    'PL4C':
      PIN_NUMBER='(0,H6,0,0,0,0,0)';
      BIDIRECTIONAL='TRUE';
      INPUT_LOAD='(-0.01,0.01)';
      OUTPUT_LOAD='(1.0,-1.0)';
    'PL6C':
      PIN_NUMBER='(0,H5,0,0,0,0,0)';
      BIDIRECTIONAL='TRUE';
      INPUT_LOAD='(-0.01,0.01)';
      OUTPUT_LOAD='(1.0,-1.0)';
    'PL6D':
      PIN_NUMBER='(0,H4,0,0,0,0,0)';
      BIDIRECTIONAL='TRUE';
      INPUT_LOAD='(-0.01,0.01)';
      OUTPUT_LOAD='(1.0,-1.0)';
    'PL8A':
      PIN_NUMBER='(0,H3,0,0,0,0,0)';
      BIDIRECTIONAL='TRUE';
      INPUT_LOAD='(-0.01,0.01)';
      OUTPUT_LOAD='(1.0,-1.0)';
    'PL8B':
      PIN_NUMBER='(0,H2,0,0,0,0,0)';
      BIDIRECTIONAL='TRUE';
      INPUT_LOAD='(-0.01,0.01)';
      OUTPUT_LOAD='(1.0,-1.0)';
    'PL9A':
      PIN_NUMBER='(0,H1,0,0,0,0,0)';
      BIDIRECTIONAL='TRUE';
      INPUT_LOAD='(-0.01,0.01)';
      OUTPUT_LOAD='(1.0,-1.0)';
    'PL3C':
      PIN_NUMBER='(0,G6,0,0,0,0,0)';
      BIDIRECTIONAL='TRUE';
      INPUT_LOAD='(-0.01,0.01)';
      OUTPUT_LOAD='(1.0,-1.0)';
    'PL4D':
      PIN_NUMBER='(0,G5,0,0,0,0,0)';
      BIDIRECTIONAL='TRUE';
      INPUT_LOAD='(-0.01,0.01)';
      OUTPUT_LOAD='(1.0,-1.0)';
    'PL5D':
      PIN_NUMBER='(0,G4,0,0,0,0,0)';
      BIDIRECTIONAL='TRUE';
      INPUT_LOAD='(-0.01,0.01)';
      OUTPUT_LOAD='(1.0,-1.0)';
    'PL7A':
      PIN_NUMBER='(0,G2,0,0,0,0,0)';
      BIDIRECTIONAL='TRUE';
      INPUT_LOAD='(-0.01,0.01)';
      OUTPUT_LOAD='(1.0,-1.0)';
    'PL7B':
      PIN_NUMBER='(0,G1,0,0,0,0,0)';
      BIDIRECTIONAL='TRUE';
      INPUT_LOAD='(-0.01,0.01)';
      OUTPUT_LOAD='(1.0,-1.0)';
    'PL2C':
      PIN_NUMBER='(0,F6,0,0,0,0,0)';
      BIDIRECTIONAL='TRUE';
      INPUT_LOAD='(-0.01,0.01)';
      OUTPUT_LOAD='(1.0,-1.0)';
    'PL2D':
      PIN_NUMBER='(0,F5,0,0,0,0,0)';
      BIDIRECTIONAL='TRUE';
      INPUT_LOAD='(-0.01,0.01)';
      OUTPUT_LOAD='(1.0,-1.0)';
    'PL5C':
      PIN_NUMBER='(0,F4,0,0,0,0,0)';
      BIDIRECTIONAL='TRUE';
      INPUT_LOAD='(-0.01,0.01)';
      OUTPUT_LOAD='(1.0,-1.0)';
    'PL6B_PCLKC5_0':
      PIN_NUMBER='(0,F3,0,0,0,0,0)';
      BIDIRECTIONAL='TRUE';
      INPUT_LOAD='(-0.01,0.01)';
      OUTPUT_LOAD='(1.0,-1.0)';
    'PL3A_L_GPLLT_FB':
      PIN_NUMBER='(0,E4,0,0,0,0,0)';
      BIDIRECTIONAL='TRUE';
      INPUT_LOAD='(-0.01,0.01)';
      OUTPUT_LOAD='(1.0,-1.0)';
    'PL5A':
      PIN_NUMBER='(0,E2,0,0,0,0,0)';
      BIDIRECTIONAL='TRUE';
      INPUT_LOAD='(-0.01,0.01)';
      OUTPUT_LOAD='(1.0,-1.0)';
    'PL6A_PCLKT5_0':
      PIN_NUMBER='(0,E1,0,0,0,0,0)';
      BIDIRECTIONAL='TRUE';
      INPUT_LOAD='(-0.01,0.01)';
      OUTPUT_LOAD='(1.0,-1.0)';
    'PL3B_L_GPLLC_FB':
      PIN_NUMBER='(0,D3,0,0,0,0,0)';
      BIDIRECTIONAL='TRUE';
      INPUT_LOAD='(-0.01,0.01)';
      OUTPUT_LOAD='(1.0,-1.0)';
    'PL5B':
      PIN_NUMBER='(0,D1,0,0,0,0,0)';
      BIDIRECTIONAL='TRUE';
      INPUT_LOAD='(-0.01,0.01)';
      OUTPUT_LOAD='(1.0,-1.0)';
    'PL2A':
      PIN_NUMBER='(0,C3,0,0,0,0,0)';
      BIDIRECTIONAL='TRUE';
      INPUT_LOAD='(-0.01,0.01)';
      OUTPUT_LOAD='(1.0,-1.0)';
    'PL2B':
      PIN_NUMBER='(0,C2,0,0,0,0,0)';
      BIDIRECTIONAL='TRUE';
      INPUT_LOAD='(-0.01,0.01)';
      OUTPUT_LOAD='(1.0,-1.0)';
    'PL4B_L_GPLLC_IN':
      PIN_NUMBER='(0,C1,0,0,0,0,0)';
      BIDIRECTIONAL='TRUE';
      INPUT_LOAD='(-0.01,0.01)';
      OUTPUT_LOAD='(1.0,-1.0)';
    'PL4A_L_GPLLT_IN':
      PIN_NUMBER='(0,B1,0,0,0,0,0)';
      BIDIRECTIONAL='TRUE';
      INPUT_LOAD='(-0.01,0.01)';
      OUTPUT_LOAD='(1.0,-1.0)';
    'PL18B':
      PIN_NUMBER='(0,AA1,0,0,0,0,0)';
      BIDIRECTIONAL='TRUE';
      INPUT_LOAD='(-0.01,0.01)';
      OUTPUT_LOAD='(1.0,-1.0)';
    'PR18B':
      PIN_NUMBER='(0,0,AA22,0,0,0,0)';
      BIDIRECTIONAL='TRUE';
      INPUT_LOAD='(-0.01,0.01)';
      OUTPUT_LOAD='(1.0,-1.0)';
    'PR4A':
      PIN_NUMBER='(0,0,B22,0,0,0,0)';
      BIDIRECTIONAL='TRUE';
      INPUT_LOAD='(-0.01,0.01)';
      OUTPUT_LOAD='(1.0,-1.0)';
    'PR2B_R_GPLLC_FB':
      PIN_NUMBER='(0,0,C21,0,0,0,0)';
      BIDIRECTIONAL='TRUE';
      INPUT_LOAD='(-0.01,0.01)';
      OUTPUT_LOAD='(1.0,-1.0)';
    'PR4B':
      PIN_NUMBER='(0,0,C22,0,0,0,0)';
      BIDIRECTIONAL='TRUE';
      INPUT_LOAD='(-0.01,0.01)';
      OUTPUT_LOAD='(1.0,-1.0)';
    'PR2A_R_GPLLT_FB':
      PIN_NUMBER='(0,0,D19,0,0,0,0)';
      BIDIRECTIONAL='TRUE';
      INPUT_LOAD='(-0.01,0.01)';
      OUTPUT_LOAD='(1.0,-1.0)';
    'PR3B_R_GPLLC_IN':
      PIN_NUMBER='(0,0,D20,0,0,0,0)';
      BIDIRECTIONAL='TRUE';
      INPUT_LOAD='(-0.01,0.01)';
      OUTPUT_LOAD='(1.0,-1.0)';
    'PR5A':
      PIN_NUMBER='(0,0,D21,0,0,0,0)';
      BIDIRECTIONAL='TRUE';
      INPUT_LOAD='(-0.01,0.01)';
      OUTPUT_LOAD='(1.0,-1.0)';
    'PR3A_R_GPLLT_IN':
      PIN_NUMBER='(0,0,E19,0,0,0,0)';
      BIDIRECTIONAL='TRUE';
      INPUT_LOAD='(-0.01,0.01)';
      OUTPUT_LOAD='(1.0,-1.0)';
    'PR5B':
      PIN_NUMBER='(0,0,E20,0,0,0,0)';
      BIDIRECTIONAL='TRUE';
      INPUT_LOAD='(-0.01,0.01)';
      OUTPUT_LOAD='(1.0,-1.0)';
    'PR6A':
      PIN_NUMBER='(0,0,E22,0,0,0,0)';
      BIDIRECTIONAL='TRUE';
      INPUT_LOAD='(-0.01,0.01)';
      OUTPUT_LOAD='(1.0,-1.0)';
    'PR2D':
      PIN_NUMBER='(0,0,F18,0,0,0,0)';
      BIDIRECTIONAL='TRUE';
      INPUT_LOAD='(-0.01,0.01)';
      OUTPUT_LOAD='(1.0,-1.0)';
    'PR6B':
      PIN_NUMBER='(0,0,F20,0,0,0,0)';
      BIDIRECTIONAL='TRUE';
      INPUT_LOAD='(-0.01,0.01)';
      OUTPUT_LOAD='(1.0,-1.0)';
    'PR2C':
      PIN_NUMBER='(0,0,G16,0,0,0,0)';
      BIDIRECTIONAL='TRUE';
      INPUT_LOAD='(-0.01,0.01)';
      OUTPUT_LOAD='(1.0,-1.0)';
    'PR3C':
      PIN_NUMBER='(0,0,G17,0,0,0,0)';
      BIDIRECTIONAL='TRUE';
      INPUT_LOAD='(-0.01,0.01)';
      OUTPUT_LOAD='(1.0,-1.0)';
    'PR4D':
      PIN_NUMBER='(0,0,G18,0,0,0,0)';
      BIDIRECTIONAL='TRUE';
      INPUT_LOAD='(-0.01,0.01)';
      OUTPUT_LOAD='(1.0,-1.0)';
    'PR7A':
      PIN_NUMBER='(0,0,G21,0,0,0,0)';
      BIDIRECTIONAL='TRUE';
      INPUT_LOAD='(-0.01,0.01)';
      OUTPUT_LOAD='(1.0,-1.0)';
    'PR7B':
      PIN_NUMBER='(0,0,G22,0,0,0,0)';
      BIDIRECTIONAL='TRUE';
      INPUT_LOAD='(-0.01,0.01)';
      OUTPUT_LOAD='(1.0,-1.0)';
    'PR3D':
      PIN_NUMBER='(0,0,H16,0,0,0,0)';
      BIDIRECTIONAL='TRUE';
      INPUT_LOAD='(-0.01,0.01)';
      OUTPUT_LOAD='(1.0,-1.0)';
    'PR4C':
      PIN_NUMBER='(0,0,H17,0,0,0,0)';
      BIDIRECTIONAL='TRUE';
      INPUT_LOAD='(-0.01,0.01)';
      OUTPUT_LOAD='(1.0,-1.0)';
    'PR8A':
      PIN_NUMBER='(0,0,H20,0,0,0,0)';
      BIDIRECTIONAL='TRUE';
      INPUT_LOAD='(-0.01,0.01)';
      OUTPUT_LOAD='(1.0,-1.0)';
    'PR8B':
      PIN_NUMBER='(0,0,H21,0,0,0,0)';
      BIDIRECTIONAL='TRUE';
      INPUT_LOAD='(-0.01,0.01)';
      OUTPUT_LOAD='(1.0,-1.0)';
    'PR5D':
      PIN_NUMBER='(0,0,J16,0,0,0,0)';
      BIDIRECTIONAL='TRUE';
      INPUT_LOAD='(-0.01,0.01)';
      OUTPUT_LOAD='(1.0,-1.0)';
    'PR5C':
      PIN_NUMBER='(0,0,J17,0,0,0,0)';
      BIDIRECTIONAL='TRUE';
      INPUT_LOAD='(-0.01,0.01)';
      OUTPUT_LOAD='(1.0,-1.0)';
    'PR6C':
      PIN_NUMBER='(0,0,J18,0,0,0,0)';
      BIDIRECTIONAL='TRUE';
      INPUT_LOAD='(-0.01,0.01)';
      OUTPUT_LOAD='(1.0,-1.0)';
    'PR6D':
      PIN_NUMBER='(0,0,J19,0,0,0,0)';
      BIDIRECTIONAL='TRUE';
      INPUT_LOAD='(-0.01,0.01)';
      OUTPUT_LOAD='(1.0,-1.0)';
    'PR7D':
      PIN_NUMBER='(0,0,K16,0,0,0,0)';
      BIDIRECTIONAL='TRUE';
      INPUT_LOAD='(-0.01,0.01)';
      OUTPUT_LOAD='(1.0,-1.0)';
    'PR7C':
      PIN_NUMBER='(0,0,K17,0,0,0,0)';
      BIDIRECTIONAL='TRUE';
      INPUT_LOAD='(-0.01,0.01)';
      OUTPUT_LOAD='(1.0,-1.0)';
    'PR9A':
      PIN_NUMBER='(0,0,K21,0,0,0,0)';
      BIDIRECTIONAL='TRUE';
      INPUT_LOAD='(-0.01,0.01)';
      OUTPUT_LOAD='(1.0,-1.0)';
    'PR9B':
      PIN_NUMBER='(0,0,K22,0,0,0,0)';
      BIDIRECTIONAL='TRUE';
      INPUT_LOAD='(-0.01,0.01)';
      OUTPUT_LOAD='(1.0,-1.0)';
    'PR8D':
      PIN_NUMBER='(0,0,L16,0,0,0,0)';
      BIDIRECTIONAL='TRUE';
      INPUT_LOAD='(-0.01,0.01)';
      OUTPUT_LOAD='(1.0,-1.0)';
    'PR8C':
      PIN_NUMBER='(0,0,L17,0,0,0,0)';
      BIDIRECTIONAL='TRUE';
      INPUT_LOAD='(-0.01,0.01)';
      OUTPUT_LOAD='(1.0,-1.0)';
    'PR9C':
      PIN_NUMBER='(0,0,L21,0,0,0,0)';
      BIDIRECTIONAL='TRUE';
      INPUT_LOAD='(-0.01,0.01)';
      OUTPUT_LOAD='(1.0,-1.0)';
    'PR9D':
      PIN_NUMBER='(0,0,L22,0,0,0,0)';
      BIDIRECTIONAL='TRUE';
      INPUT_LOAD='(-0.01,0.01)';
      OUTPUT_LOAD='(1.0,-1.0)';
    'PR13D':
      PIN_NUMBER='(0,0,M18,0,0,0,0)';
      BIDIRECTIONAL='TRUE';
      INPUT_LOAD='(-0.01,0.01)';
      OUTPUT_LOAD='(1.0,-1.0)';
    'PR13C':
      PIN_NUMBER='(0,0,M19,0,0,0,0)';
      BIDIRECTIONAL='TRUE';
      INPUT_LOAD='(-0.01,0.01)';
      OUTPUT_LOAD='(1.0,-1.0)';
    'PR14C':
      PIN_NUMBER='(0,0,M20,0,0,0,0)';
      BIDIRECTIONAL='TRUE';
      INPUT_LOAD='(-0.01,0.01)';
      OUTPUT_LOAD='(1.0,-1.0)';
    'PR14D':
      PIN_NUMBER='(0,0,N18,0,0,0,0)';
      BIDIRECTIONAL='TRUE';
      INPUT_LOAD='(-0.01,0.01)';
      OUTPUT_LOAD='(1.0,-1.0)';
    'PR10C':
      PIN_NUMBER='(0,0,N20,0,0,0,0)';
      BIDIRECTIONAL='TRUE';
      INPUT_LOAD='(-0.01,0.01)';
      OUTPUT_LOAD='(1.0,-1.0)';
    'PR10B_PCLKC1_0':
      PIN_NUMBER='(0,0,N21,0,0,0,0)';
      BIDIRECTIONAL='TRUE';
      INPUT_LOAD='(-0.01,0.01)';
      OUTPUT_LOAD='(1.0,-1.0)';
    'PR10A_PCLKT1_0':
      PIN_NUMBER='(0,0,N22,0,0,0,0)';
      BIDIRECTIONAL='TRUE';
      INPUT_LOAD='(-0.01,0.01)';
      OUTPUT_LOAD='(1.0,-1.0)';
    'PR15D':
      PIN_NUMBER='(0,0,P18,0,0,0,0)';
      BIDIRECTIONAL='TRUE';
      INPUT_LOAD='(-0.01,0.01)';
      OUTPUT_LOAD='(1.0,-1.0)';
    'PR15C':
      PIN_NUMBER='(0,0,P19,0,0,0,0)';
      BIDIRECTIONAL='TRUE';
      INPUT_LOAD='(-0.01,0.01)';
      OUTPUT_LOAD='(1.0,-1.0)';
    'PR13A':
      PIN_NUMBER='(0,0,P20,0,0,0,0)';
      BIDIRECTIONAL='TRUE';
      INPUT_LOAD='(-0.01,0.01)';
      OUTPUT_LOAD='(1.0,-1.0)';
    'PR10D':
      PIN_NUMBER='(0,0,P21,0,0,0,0)';
      BIDIRECTIONAL='TRUE';
      INPUT_LOAD='(-0.01,0.01)';
      OUTPUT_LOAD='(1.0,-1.0)';
    'PR19C':
      PIN_NUMBER='(0,0,R16,0,0,0,0)';
      BIDIRECTIONAL='TRUE';
      INPUT_LOAD='(-0.01,0.01)';
      OUTPUT_LOAD='(1.0,-1.0)';
    'PR18D':
      PIN_NUMBER='(0,0,R17,0,0,0,0)';
      BIDIRECTIONAL='TRUE';
      INPUT_LOAD='(-0.01,0.01)';
      OUTPUT_LOAD='(1.0,-1.0)';
    'PR16D':
      PIN_NUMBER='(0,0,R18,0,0,0,0)';
      BIDIRECTIONAL='TRUE';
      INPUT_LOAD='(-0.01,0.01)';
      OUTPUT_LOAD='(1.0,-1.0)';
    'PR16C':
      PIN_NUMBER='(0,0,R19,0,0,0,0)';
      BIDIRECTIONAL='TRUE';
      INPUT_LOAD='(-0.01,0.01)';
      OUTPUT_LOAD='(1.0,-1.0)';
    'PR14B':
      PIN_NUMBER='(0,0,R20,0,0,0,0)';
      BIDIRECTIONAL='TRUE';
      INPUT_LOAD='(-0.01,0.01)';
      OUTPUT_LOAD='(1.0,-1.0)';
    'PR14A':
      PIN_NUMBER='(0,0,R21,0,0,0,0)';
      BIDIRECTIONAL='TRUE';
      INPUT_LOAD='(-0.01,0.01)';
      OUTPUT_LOAD='(1.0,-1.0)';
    'PR13B':
      PIN_NUMBER='(0,0,R22,0,0,0,0)';
      BIDIRECTIONAL='TRUE';
      INPUT_LOAD='(-0.01,0.01)';
      OUTPUT_LOAD='(1.0,-1.0)';
    'PR19D':
      PIN_NUMBER='(0,0,T17,0,0,0,0)';
      BIDIRECTIONAL='TRUE';
      INPUT_LOAD='(-0.01,0.01)';
      OUTPUT_LOAD='(1.0,-1.0)';
    'PR18C':
      PIN_NUMBER='(0,0,T18,0,0,0,0)';
      BIDIRECTIONAL='TRUE';
      INPUT_LOAD='(-0.01,0.01)';
      OUTPUT_LOAD='(1.0,-1.0)';
    'PR17C':
      PIN_NUMBER='(0,0,T19,0,0,0,0)';
      BIDIRECTIONAL='TRUE';
      INPUT_LOAD='(-0.01,0.01)';
      OUTPUT_LOAD='(1.0,-1.0)';
    'PR15B':
      PIN_NUMBER='(0,0,T21,0,0,0,0)';
      BIDIRECTIONAL='TRUE';
      INPUT_LOAD='(-0.01,0.01)';
      OUTPUT_LOAD='(1.0,-1.0)';
    'PR15A':
      PIN_NUMBER='(0,0,T22,0,0,0,0)';
      BIDIRECTIONAL='TRUE';
      INPUT_LOAD='(-0.01,0.01)';
      OUTPUT_LOAD='(1.0,-1.0)';
    'PR20D':
      PIN_NUMBER='(0,0,U17,0,0,0,0)';
      BIDIRECTIONAL='TRUE';
      INPUT_LOAD='(-0.01,0.01)';
      OUTPUT_LOAD='(1.0,-1.0)';
    'PR20C':
      PIN_NUMBER='(0,0,U18,0,0,0,0)';
      BIDIRECTIONAL='TRUE';
      INPUT_LOAD='(-0.01,0.01)';
      OUTPUT_LOAD='(1.0,-1.0)';
    'PR17D':
      PIN_NUMBER='(0,0,U19,0,0,0,0)';
      BIDIRECTIONAL='TRUE';
      INPUT_LOAD='(-0.01,0.01)';
      OUTPUT_LOAD='(1.0,-1.0)';
    'PR16A':
      PIN_NUMBER='(0,0,U20,0,0,0,0)';
      BIDIRECTIONAL='TRUE';
      INPUT_LOAD='(-0.01,0.01)';
      OUTPUT_LOAD='(1.0,-1.0)';
    'PR19B':
      PIN_NUMBER='(0,0,V19,0,0,0,0)';
      BIDIRECTIONAL='TRUE';
      INPUT_LOAD='(-0.01,0.01)';
      OUTPUT_LOAD='(1.0,-1.0)';
    'PR17B':
      PIN_NUMBER='(0,0,V21,0,0,0,0)';
      BIDIRECTIONAL='TRUE';
      INPUT_LOAD='(-0.01,0.01)';
      OUTPUT_LOAD='(1.0,-1.0)';
    'PR16B':
      PIN_NUMBER='(0,0,V22,0,0,0,0)';
      BIDIRECTIONAL='TRUE';
      INPUT_LOAD='(-0.01,0.01)';
      OUTPUT_LOAD='(1.0,-1.0)';
    'PR19A':
      PIN_NUMBER='(0,0,W20,0,0,0,0)';
      BIDIRECTIONAL='TRUE';
      INPUT_LOAD='(-0.01,0.01)';
      OUTPUT_LOAD='(1.0,-1.0)';
    'PR17A':
      PIN_NUMBER='(0,0,W22,0,0,0,0)';
      BIDIRECTIONAL='TRUE';
      INPUT_LOAD='(-0.01,0.01)';
      OUTPUT_LOAD='(1.0,-1.0)';
    'PR20B':
      PIN_NUMBER='(0,0,Y20,0,0,0,0)';
      BIDIRECTIONAL='TRUE';
      INPUT_LOAD='(-0.01,0.01)';
      OUTPUT_LOAD='(1.0,-1.0)';
    'PR20A':
      PIN_NUMBER='(0,0,Y21,0,0,0,0)';
      BIDIRECTIONAL='TRUE';
      INPUT_LOAD='(-0.01,0.01)';
      OUTPUT_LOAD='(1.0,-1.0)';
    'PR18A':
      PIN_NUMBER='(0,0,Y22,0,0,0,0)';
      BIDIRECTIONAL='TRUE';
      INPUT_LOAD='(-0.01,0.01)';
      OUTPUT_LOAD='(1.0,-1.0)';
    'PT11A':
      PIN_NUMBER='(0,0,0,A2,0,0,0)';
      BIDIRECTIONAL='TRUE';
      INPUT_LOAD='(-0.01,0.01)';
      OUTPUT_LOAD='(1.0,-1.0)';
    'PT11B':
      PIN_NUMBER='(0,0,0,A3,0,0,0)';
      BIDIRECTIONAL='TRUE';
      INPUT_LOAD='(-0.01,0.01)';
      OUTPUT_LOAD='(1.0,-1.0)';
    'PT12C':
      PIN_NUMBER='(0,0,0,A5,0,0,0)';
      BIDIRECTIONAL='TRUE';
      INPUT_LOAD='(-0.01,0.01)';
      OUTPUT_LOAD='(1.0,-1.0)';
    'PT13C_TDO':
      PIN_NUMBER='(0,0,0,A6,0,0,0)';
      BIDIRECTIONAL='TRUE';
      INPUT_LOAD='(-0.01,0.01)';
      OUTPUT_LOAD='(1.0,-1.0)';
    'PT14B':
      PIN_NUMBER='(0,0,0,A7,0,0,0)';
      BIDIRECTIONAL='TRUE';
      INPUT_LOAD='(-0.01,0.01)';
      OUTPUT_LOAD='(1.0,-1.0)';
    'PT15C_TCK':
      PIN_NUMBER='(0,0,0,A8,0,0,0)';
      BIDIRECTIONAL='TRUE';
      INPUT_LOAD='(-0.01,0.01)';
      OUTPUT_LOAD='(1.0,-1.0)';
    'PT19D':
      PIN_NUMBER='(0,0,0,A10,0,0,0)';
      BIDIRECTIONAL='TRUE';
      INPUT_LOAD='(-0.01,0.01)';
      OUTPUT_LOAD='(1.0,-1.0)';
    'PT19B':
      PIN_NUMBER='(0,0,0,A11,0,0,0)';
      BIDIRECTIONAL='TRUE';
      INPUT_LOAD='(-0.01,0.01)';
      OUTPUT_LOAD='(1.0,-1.0)';
    'PT20A':
      PIN_NUMBER='(0,0,0,A12,0,0,0)';
      BIDIRECTIONAL='TRUE';
      INPUT_LOAD='(-0.01,0.01)';
      OUTPUT_LOAD='(1.0,-1.0)';
    'PT20C_SCL_PCLKT0_0':
      PIN_NUMBER='(0,0,0,A13,0,0,0)';
      BIDIRECTIONAL='TRUE';
      INPUT_LOAD='(-0.01,0.01)';
      OUTPUT_LOAD='(1.0,-1.0)';
    'PT23C_JTAGENB':
      PIN_NUMBER='(0,0,0,A16,0,0,0)';
      BIDIRECTIONAL='TRUE';
      INPUT_LOAD='(-0.01,0.01)';
      OUTPUT_LOAD='(1.0,-1.0)';
    'PT24B':
      PIN_NUMBER='(0,0,0,A17,0,0,0)';
      BIDIRECTIONAL='TRUE';
      INPUT_LOAD='(-0.01,0.01)';
      OUTPUT_LOAD='(1.0,-1.0)';
    'PT26C':
      PIN_NUMBER='(0,0,0,A20,0,0,0)';
      BIDIRECTIONAL='TRUE';
      INPUT_LOAD='(-0.01,0.01)';
      OUTPUT_LOAD='(1.0,-1.0)';
    'PT26D':
      PIN_NUMBER='(0,0,0,A21,0,0,0)';
      BIDIRECTIONAL='TRUE';
      INPUT_LOAD='(-0.01,0.01)';
      OUTPUT_LOAD='(1.0,-1.0)';
    'PT9B':
      PIN_NUMBER='(0,0,0,B3,0,0,0)';
      BIDIRECTIONAL='TRUE';
      INPUT_LOAD='(-0.01,0.01)';
      OUTPUT_LOAD='(1.0,-1.0)';
    'PT14A':
      PIN_NUMBER='(0,0,0,B7,0,0,0)';
      BIDIRECTIONAL='TRUE';
      INPUT_LOAD='(-0.01,0.01)';
      OUTPUT_LOAD='(1.0,-1.0)';
    'PT18A_PCLKT0_1':
      PIN_NUMBER='(0,0,0,B9,0,0,0)';
      BIDIRECTIONAL='TRUE';
      INPUT_LOAD='(-0.01,0.01)';
      OUTPUT_LOAD='(1.0,-1.0)';
    'PT19C':
      PIN_NUMBER='(0,0,0,B10,0,0,0)';
      BIDIRECTIONAL='TRUE';
      INPUT_LOAD='(-0.01,0.01)';
      OUTPUT_LOAD='(1.0,-1.0)';
    'PT19A':
      PIN_NUMBER='(0,0,0,B11,0,0,0)';
      BIDIRECTIONAL='TRUE';
      INPUT_LOAD='(-0.01,0.01)';
      OUTPUT_LOAD='(1.0,-1.0)';
    'PT20B':
      PIN_NUMBER='(0,0,0,B12,0,0,0)';
      BIDIRECTIONAL='TRUE';
      INPUT_LOAD='(-0.01,0.01)';
      OUTPUT_LOAD='(1.0,-1.0)';
    'PT20D_SDA_PCLKC0_0':
      PIN_NUMBER='(0,0,0,B13,0,0,0)';
      BIDIRECTIONAL='TRUE';
      INPUT_LOAD='(-0.01,0.01)';
      OUTPUT_LOAD='(1.0,-1.0)';
    'PT21B':
      PIN_NUMBER='(0,0,0,B14,0,0,0)';
      BIDIRECTIONAL='TRUE';
      INPUT_LOAD='(-0.01,0.01)';
      OUTPUT_LOAD='(1.0,-1.0)';
    'PT22C':
      PIN_NUMBER='(0,0,0,B15,0,0,0)';
      BIDIRECTIONAL='TRUE';
      INPUT_LOAD='(-0.01,0.01)';
      OUTPUT_LOAD='(1.0,-1.0)';
    'PT23D_PROGRAMN':
      PIN_NUMBER='(0,0,0,B16,0,0,0)';
      BIDIRECTIONAL='TRUE';
      INPUT_LOAD='(-0.01,0.01)';
      OUTPUT_LOAD='(1.0,-1.0)';
    'PT25B':
      PIN_NUMBER='(0,0,0,B19,0,0,0)';
      BIDIRECTIONAL='TRUE';
      INPUT_LOAD='(-0.01,0.01)';
      OUTPUT_LOAD='(1.0,-1.0)';
    'PT28C_INITN':
      PIN_NUMBER='(0,0,0,B20,0,0,0)';
      BIDIRECTIONAL='TRUE';
      INPUT_LOAD='(-0.01,0.01)';
      OUTPUT_LOAD='(1.0,-1.0)';
    'PT10B':
      PIN_NUMBER='(0,0,0,C4,0,0,0)';
      BIDIRECTIONAL='TRUE';
      INPUT_LOAD='(-0.01,0.01)';
      OUTPUT_LOAD='(1.0,-1.0)';
    'PT12D':
      PIN_NUMBER='(0,0,0,C6,0,0,0)';
      BIDIRECTIONAL='TRUE';
      INPUT_LOAD='(-0.01,0.01)';
      OUTPUT_LOAD='(1.0,-1.0)';
    'PT13D_TDI':
      PIN_NUMBER='(0,0,0,C7,0,0,0)';
      BIDIRECTIONAL='TRUE';
      INPUT_LOAD='(-0.01,0.01)';
      OUTPUT_LOAD='(1.0,-1.0)';
    'PT15D_TMS':
      PIN_NUMBER='(0,0,0,C9,0,0,0)';
      BIDIRECTIONAL='TRUE';
      INPUT_LOAD='(-0.01,0.01)';
      OUTPUT_LOAD='(1.0,-1.0)';
    'PT18B_PCLKC0_1':
      PIN_NUMBER='(0,0,0,C10,0,0,0)';
      BIDIRECTIONAL='TRUE';
      INPUT_LOAD='(-0.01,0.01)';
      OUTPUT_LOAD='(1.0,-1.0)';
    'PT14D':
      PIN_NUMBER='(0,0,0,C11,0,0,0)';
      BIDIRECTIONAL='TRUE';
      INPUT_LOAD='(-0.01,0.01)';
      OUTPUT_LOAD='(1.0,-1.0)';
    'PT21A':
      PIN_NUMBER='(0,0,0,C13,0,0,0)';
      BIDIRECTIONAL='TRUE';
      INPUT_LOAD='(-0.01,0.01)';
      OUTPUT_LOAD='(1.0,-1.0)';
    'PT22D':
      PIN_NUMBER='(0,0,0,C15,0,0,0)';
      BIDIRECTIONAL='TRUE';
      INPUT_LOAD='(-0.01,0.01)';
      OUTPUT_LOAD='(1.0,-1.0)';
    'PT24A':
      PIN_NUMBER='(0,0,0,C16,0,0,0)';
      BIDIRECTIONAL='TRUE';
      INPUT_LOAD='(-0.01,0.01)';
      OUTPUT_LOAD='(1.0,-1.0)';
    'PT25A':
      PIN_NUMBER='(0,0,0,C18,0,0,0)';
      BIDIRECTIONAL='TRUE';
      INPUT_LOAD='(-0.01,0.01)';
      OUTPUT_LOAD='(1.0,-1.0)';
    'PT27A':
      PIN_NUMBER='(0,0,0,C19,0,0,0)';
      BIDIRECTIONAL='TRUE';
      INPUT_LOAD='(-0.01,0.01)';
      OUTPUT_LOAD='(1.0,-1.0)';
    'PT28D_DONE':
      PIN_NUMBER='(0,0,0,C20,0,0,0)';
      BIDIRECTIONAL='TRUE';
      INPUT_LOAD='(-0.01,0.01)';
      OUTPUT_LOAD='(1.0,-1.0)';
    'PT9A':
      PIN_NUMBER='(0,0,0,D4,0,0,0)';
      BIDIRECTIONAL='TRUE';
      INPUT_LOAD='(-0.01,0.01)';
      OUTPUT_LOAD='(1.0,-1.0)';
    'PT10A':
      PIN_NUMBER='(0,0,0,D5,0,0,0)';
      BIDIRECTIONAL='TRUE';
      INPUT_LOAD='(-0.01,0.01)';
      OUTPUT_LOAD='(1.0,-1.0)';
    'PT12A':
      PIN_NUMBER='(0,0,0,D6,0,0,0)';
      BIDIRECTIONAL='TRUE';
      INPUT_LOAD='(-0.01,0.01)';
      OUTPUT_LOAD='(1.0,-1.0)';
    'PT12B':
      PIN_NUMBER='(0,0,0,D7,0,0,0)';
      BIDIRECTIONAL='TRUE';
      INPUT_LOAD='(-0.01,0.01)';
      OUTPUT_LOAD='(1.0,-1.0)';
    'PT13B':
      PIN_NUMBER='(0,0,0,D9,0,0,0)';
      BIDIRECTIONAL='TRUE';
      INPUT_LOAD='(-0.01,0.01)';
      OUTPUT_LOAD='(1.0,-1.0)';
    'PT15B':
      PIN_NUMBER='(0,0,0,D11,0,0,0)';
      BIDIRECTIONAL='TRUE';
      INPUT_LOAD='(-0.01,0.01)';
      OUTPUT_LOAD='(1.0,-1.0)';
    'PT22A':
      PIN_NUMBER='(0,0,0,D12,0,0,0)';
      BIDIRECTIONAL='TRUE';
      INPUT_LOAD='(-0.01,0.01)';
      OUTPUT_LOAD='(1.0,-1.0)';
    'PT24C':
      PIN_NUMBER='(0,0,0,D15,0,0,0)';
      BIDIRECTIONAL='TRUE';
      INPUT_LOAD='(-0.01,0.01)';
      OUTPUT_LOAD='(1.0,-1.0)';
    'PT25C':
      PIN_NUMBER='(0,0,0,D16,0,0,0)';
      BIDIRECTIONAL='TRUE';
      INPUT_LOAD='(-0.01,0.01)';
      OUTPUT_LOAD='(1.0,-1.0)';
    'PT25D':
      PIN_NUMBER='(0,0,0,D17,0,0,0)';
      BIDIRECTIONAL='TRUE';
      INPUT_LOAD='(-0.01,0.01)';
      OUTPUT_LOAD='(1.0,-1.0)';
    'PT27B':
      PIN_NUMBER='(0,0,0,D18,0,0,0)';
      BIDIRECTIONAL='TRUE';
      INPUT_LOAD='(-0.01,0.01)';
      OUTPUT_LOAD='(1.0,-1.0)';
    'PT9D':
      PIN_NUMBER='(0,0,0,E6,0,0,0)';
      BIDIRECTIONAL='TRUE';
      INPUT_LOAD='(-0.01,0.01)';
      OUTPUT_LOAD='(1.0,-1.0)';
    'PT11D':
      PIN_NUMBER='(0,0,0,E7,0,0,0)';
      BIDIRECTIONAL='TRUE';
      INPUT_LOAD='(-0.01,0.01)';
      OUTPUT_LOAD='(1.0,-1.0)';
    'PT13A':
      PIN_NUMBER='(0,0,0,E9,0,0,0)';
      BIDIRECTIONAL='TRUE';
      INPUT_LOAD='(-0.01,0.01)';
      OUTPUT_LOAD='(1.0,-1.0)';
    'PT14C':
      PIN_NUMBER='(0,0,0,E10,0,0,0)';
      BIDIRECTIONAL='TRUE';
      INPUT_LOAD='(-0.01,0.01)';
      OUTPUT_LOAD='(1.0,-1.0)';
    'PT15A':
      PIN_NUMBER='(0,0,0,E11,0,0,0)';
      BIDIRECTIONAL='TRUE';
      INPUT_LOAD='(-0.01,0.01)';
      OUTPUT_LOAD='(1.0,-1.0)';
    'PT22B':
      PIN_NUMBER='(0,0,0,E12,0,0,0)';
      BIDIRECTIONAL='TRUE';
      INPUT_LOAD='(-0.01,0.01)';
      OUTPUT_LOAD='(1.0,-1.0)';
    'PT24D':
      PIN_NUMBER='(0,0,0,E15,0,0,0)';
      BIDIRECTIONAL='TRUE';
      INPUT_LOAD='(-0.01,0.01)';
      OUTPUT_LOAD='(1.0,-1.0)';
    'PT26A':
      PIN_NUMBER='(0,0,0,E16,0,0,0)';
      BIDIRECTIONAL='TRUE';
      INPUT_LOAD='(-0.01,0.01)';
      OUTPUT_LOAD='(1.0,-1.0)';
    'PT28A':
      PIN_NUMBER='(0,0,0,E17,0,0,0)';
      BIDIRECTIONAL='TRUE';
      INPUT_LOAD='(-0.01,0.01)';
      OUTPUT_LOAD='(1.0,-1.0)';
    'PT11C':
      PIN_NUMBER='(0,0,0,F8,0,0,0)';
      BIDIRECTIONAL='TRUE';
      INPUT_LOAD='(-0.01,0.01)';
      OUTPUT_LOAD='(1.0,-1.0)';
    'PT18C':
      PIN_NUMBER='(0,0,0,F11,0,0,0)';
      BIDIRECTIONAL='TRUE';
      INPUT_LOAD='(-0.01,0.01)';
      OUTPUT_LOAD='(1.0,-1.0)';
    'PT21D':
      PIN_NUMBER='(0,0,0,F12,0,0,0)';
      BIDIRECTIONAL='TRUE';
      INPUT_LOAD='(-0.01,0.01)';
      OUTPUT_LOAD='(1.0,-1.0)';
    'PT23B':
      PIN_NUMBER='(0,0,0,F13,0,0,0)';
      BIDIRECTIONAL='TRUE';
      INPUT_LOAD='(-0.01,0.01)';
      OUTPUT_LOAD='(1.0,-1.0)';
    'PT26B':
      PIN_NUMBER='(0,0,0,F15,0,0,0)';
      BIDIRECTIONAL='TRUE';
      INPUT_LOAD='(-0.01,0.01)';
      OUTPUT_LOAD='(1.0,-1.0)';
    'PT27D':
      PIN_NUMBER='(0,0,0,F16,0,0,0)';
      BIDIRECTIONAL='TRUE';
      INPUT_LOAD='(-0.01,0.01)';
      OUTPUT_LOAD='(1.0,-1.0)';
    'PT28B':
      PIN_NUMBER='(0,0,0,F17,0,0,0)';
      BIDIRECTIONAL='TRUE';
      INPUT_LOAD='(-0.01,0.01)';
      OUTPUT_LOAD='(1.0,-1.0)';
    'PT9C':
      PIN_NUMBER='(0,0,0,G7,0,0,0)';
      BIDIRECTIONAL='TRUE';
      INPUT_LOAD='(-0.01,0.01)';
      OUTPUT_LOAD='(1.0,-1.0)';
    'PT10D':
      PIN_NUMBER='(0,0,0,G8,0,0,0)';
      BIDIRECTIONAL='TRUE';
      INPUT_LOAD='(-0.01,0.01)';
      OUTPUT_LOAD='(1.0,-1.0)';
    'PT18D':
      PIN_NUMBER='(0,0,0,G11,0,0,0)';
      BIDIRECTIONAL='TRUE';
      INPUT_LOAD='(-0.01,0.01)';
      OUTPUT_LOAD='(1.0,-1.0)';
    'PT21C':
      PIN_NUMBER='(0,0,0,G12,0,0,0)';
      BIDIRECTIONAL='TRUE';
      INPUT_LOAD='(-0.01,0.01)';
      OUTPUT_LOAD='(1.0,-1.0)';
    'PT23A':
      PIN_NUMBER='(0,0,0,G13,0,0,0)';
      BIDIRECTIONAL='TRUE';
      INPUT_LOAD='(-0.01,0.01)';
      OUTPUT_LOAD='(1.0,-1.0)';
    'PT27C':
      PIN_NUMBER='(0,0,0,G15,0,0,0)';
      BIDIRECTIONAL='TRUE';
      INPUT_LOAD='(-0.01,0.01)';
      OUTPUT_LOAD='(1.0,-1.0)';
    'NC'<0>:
      PIN_NUMBER='(0,0,0,0,A4,0,0)';
      PINUSE='NC';
      NO_LOAD_CHECK='Both';
      NO_IO_CHECK='Both';
      NO_ASSERT_CHECK='TRUE';
      NO_DIR_CHECK='TRUE';
      ALLOW_CONNECT='TRUE';
    'NC'<1>:
      PIN_NUMBER='(0,0,0,0,A15,0,0)';
      PINUSE='NC';
      NO_LOAD_CHECK='Both';
      NO_IO_CHECK='Both';
      NO_ASSERT_CHECK='TRUE';
      NO_DIR_CHECK='TRUE';
      ALLOW_CONNECT='TRUE';
    'NC'<2>:
      PIN_NUMBER='(0,0,0,0,A18,0,0)';
      PINUSE='NC';
      NO_LOAD_CHECK='Both';
      NO_IO_CHECK='Both';
      NO_ASSERT_CHECK='TRUE';
      NO_DIR_CHECK='TRUE';
      ALLOW_CONNECT='TRUE';
    'NC'<3>:
      PIN_NUMBER='(0,0,0,0,A19,0,0)';
      PINUSE='NC';
      NO_LOAD_CHECK='Both';
      NO_IO_CHECK='Both';
      NO_ASSERT_CHECK='TRUE';
      NO_DIR_CHECK='TRUE';
      ALLOW_CONNECT='TRUE';
    'NC'<4>:
      PIN_NUMBER='(0,0,0,0,AA5,0,0)';
      PINUSE='NC';
      NO_LOAD_CHECK='Both';
      NO_IO_CHECK='Both';
      NO_ASSERT_CHECK='TRUE';
      NO_DIR_CHECK='TRUE';
      ALLOW_CONNECT='TRUE';
    'NC'<5>:
      PIN_NUMBER='(0,0,0,0,AA15,0,0)';
      PINUSE='NC';
      NO_LOAD_CHECK='Both';
      NO_IO_CHECK='Both';
      NO_ASSERT_CHECK='TRUE';
      NO_DIR_CHECK='TRUE';
      ALLOW_CONNECT='TRUE';
    'NC'<6>:
      PIN_NUMBER='(0,0,0,0,AA18,0,0)';
      PINUSE='NC';
      NO_LOAD_CHECK='Both';
      NO_IO_CHECK='Both';
      NO_ASSERT_CHECK='TRUE';
      NO_DIR_CHECK='TRUE';
      ALLOW_CONNECT='TRUE';
    'NC'<7>:
      PIN_NUMBER='(0,0,0,0,AA19,0,0)';
      PINUSE='NC';
      NO_LOAD_CHECK='Both';
      NO_IO_CHECK='Both';
      NO_ASSERT_CHECK='TRUE';
      NO_DIR_CHECK='TRUE';
      ALLOW_CONNECT='TRUE';
    'NC'<8>:
      PIN_NUMBER='(0,0,0,0,AB4,0,0)';
      PINUSE='NC';
      NO_LOAD_CHECK='Both';
      NO_IO_CHECK='Both';
      NO_ASSERT_CHECK='TRUE';
      NO_DIR_CHECK='TRUE';
      ALLOW_CONNECT='TRUE';
    'NC'<9>:
      PIN_NUMBER='(0,0,0,0,AB5,0,0)';
      PINUSE='NC';
      NO_LOAD_CHECK='Both';
      NO_IO_CHECK='Both';
      NO_ASSERT_CHECK='TRUE';
      NO_DIR_CHECK='TRUE';
      ALLOW_CONNECT='TRUE';
    'NC'<10>:
      PIN_NUMBER='(0,0,0,0,AB8,0,0)';
      PINUSE='NC';
      NO_LOAD_CHECK='Both';
      NO_IO_CHECK='Both';
      NO_ASSERT_CHECK='TRUE';
      NO_DIR_CHECK='TRUE';
      ALLOW_CONNECT='TRUE';
    'NC'<11>:
      PIN_NUMBER='(0,0,0,0,AB19,0,0)';
      PINUSE='NC';
      NO_LOAD_CHECK='Both';
      NO_IO_CHECK='Both';
      NO_ASSERT_CHECK='TRUE';
      NO_DIR_CHECK='TRUE';
      ALLOW_CONNECT='TRUE';
    'NC'<12>:
      PIN_NUMBER='(0,0,0,0,B4,0,0)';
      PINUSE='NC';
      NO_LOAD_CHECK='Both';
      NO_IO_CHECK='Both';
      NO_ASSERT_CHECK='TRUE';
      NO_DIR_CHECK='TRUE';
      ALLOW_CONNECT='TRUE';
    'NC'<13>:
      PIN_NUMBER='(0,0,0,0,B5,0,0)';
      PINUSE='NC';
      NO_LOAD_CHECK='Both';
      NO_IO_CHECK='Both';
      NO_ASSERT_CHECK='TRUE';
      NO_DIR_CHECK='TRUE';
      ALLOW_CONNECT='TRUE';
    'NC'<14>:
      PIN_NUMBER='(0,0,0,0,B8,0,0)';
      PINUSE='NC';
      NO_LOAD_CHECK='Both';
      NO_IO_CHECK='Both';
      NO_ASSERT_CHECK='TRUE';
      NO_DIR_CHECK='TRUE';
      ALLOW_CONNECT='TRUE';
    'NC'<15>:
      PIN_NUMBER='(0,0,0,0,B18,0,0)';
      PINUSE='NC';
      NO_LOAD_CHECK='Both';
      NO_IO_CHECK='Both';
      NO_ASSERT_CHECK='TRUE';
      NO_DIR_CHECK='TRUE';
      ALLOW_CONNECT='TRUE';
    'NC'<16>:
      PIN_NUMBER='(0,0,0,0,C5,0,0)';
      PINUSE='NC';
      NO_LOAD_CHECK='Both';
      NO_IO_CHECK='Both';
      NO_ASSERT_CHECK='TRUE';
      NO_DIR_CHECK='TRUE';
      ALLOW_CONNECT='TRUE';
    'NC'<17>:
      PIN_NUMBER='(0,0,0,0,C8,0,0)';
      PINUSE='NC';
      NO_LOAD_CHECK='Both';
      NO_IO_CHECK='Both';
      NO_ASSERT_CHECK='TRUE';
      NO_DIR_CHECK='TRUE';
      ALLOW_CONNECT='TRUE';
    'NC'<18>:
      PIN_NUMBER='(0,0,0,0,C12,0,0)';
      PINUSE='NC';
      NO_LOAD_CHECK='Both';
      NO_IO_CHECK='Both';
      NO_ASSERT_CHECK='TRUE';
      NO_DIR_CHECK='TRUE';
      ALLOW_CONNECT='TRUE';
    'NC'<19>:
      PIN_NUMBER='(0,0,0,0,C14,0,0)';
      PINUSE='NC';
      NO_LOAD_CHECK='Both';
      NO_IO_CHECK='Both';
      NO_ASSERT_CHECK='TRUE';
      NO_DIR_CHECK='TRUE';
      ALLOW_CONNECT='TRUE';
    'NC'<20>:
      PIN_NUMBER='(0,0,0,0,C17,0,0)';
      PINUSE='NC';
      NO_LOAD_CHECK='Both';
      NO_IO_CHECK='Both';
      NO_ASSERT_CHECK='TRUE';
      NO_DIR_CHECK='TRUE';
      ALLOW_CONNECT='TRUE';
    'NC'<21>:
      PIN_NUMBER='(0,0,0,0,D2,0,0)';
      PINUSE='NC';
      NO_LOAD_CHECK='Both';
      NO_IO_CHECK='Both';
      NO_ASSERT_CHECK='TRUE';
      NO_DIR_CHECK='TRUE';
      ALLOW_CONNECT='TRUE';
    'NC'<22>:
      PIN_NUMBER='(0,0,0,0,D8,0,0)';
      PINUSE='NC';
      NO_LOAD_CHECK='Both';
      NO_IO_CHECK='Both';
      NO_ASSERT_CHECK='TRUE';
      NO_DIR_CHECK='TRUE';
      ALLOW_CONNECT='TRUE';
    'NC'<23>:
      PIN_NUMBER='(0,0,0,0,D14,0,0)';
      PINUSE='NC';
      NO_LOAD_CHECK='Both';
      NO_IO_CHECK='Both';
      NO_ASSERT_CHECK='TRUE';
      NO_DIR_CHECK='TRUE';
      ALLOW_CONNECT='TRUE';
    'NC'<24>:
      PIN_NUMBER='(0,0,0,0,D22,0,0)';
      PINUSE='NC';
      NO_LOAD_CHECK='Both';
      NO_IO_CHECK='Both';
      NO_ASSERT_CHECK='TRUE';
      NO_DIR_CHECK='TRUE';
      ALLOW_CONNECT='TRUE';
    'NC'<25>:
      PIN_NUMBER='(0,0,0,0,E3,0,0)';
      PINUSE='NC';
      NO_LOAD_CHECK='Both';
      NO_IO_CHECK='Both';
      NO_ASSERT_CHECK='TRUE';
      NO_DIR_CHECK='TRUE';
      ALLOW_CONNECT='TRUE';
    'NC'<26>:
      PIN_NUMBER='(0,0,0,0,E8,0,0)';
      PINUSE='NC';
      NO_LOAD_CHECK='Both';
      NO_IO_CHECK='Both';
      NO_ASSERT_CHECK='TRUE';
      NO_DIR_CHECK='TRUE';
      ALLOW_CONNECT='TRUE';
    'NC'<27>:
      PIN_NUMBER='(0,0,0,0,E13,0,0)';
      PINUSE='NC';
      NO_LOAD_CHECK='Both';
      NO_IO_CHECK='Both';
      NO_ASSERT_CHECK='TRUE';
      NO_DIR_CHECK='TRUE';
      ALLOW_CONNECT='TRUE';
    'NC'<28>:
      PIN_NUMBER='(0,0,0,0,E14,0,0)';
      PINUSE='NC';
      NO_LOAD_CHECK='Both';
      NO_IO_CHECK='Both';
      NO_ASSERT_CHECK='TRUE';
      NO_DIR_CHECK='TRUE';
      ALLOW_CONNECT='TRUE';
    'NC'<29>:
      PIN_NUMBER='(0,0,0,0,E21,0,0)';
      PINUSE='NC';
      NO_LOAD_CHECK='Both';
      NO_IO_CHECK='Both';
      NO_ASSERT_CHECK='TRUE';
      NO_DIR_CHECK='TRUE';
      ALLOW_CONNECT='TRUE';
    'NC'<30>:
      PIN_NUMBER='(0,0,0,0,F1,0,0)';
      PINUSE='NC';
      NO_LOAD_CHECK='Both';
      NO_IO_CHECK='Both';
      NO_ASSERT_CHECK='TRUE';
      NO_DIR_CHECK='TRUE';
      ALLOW_CONNECT='TRUE';
    'NC'<31>:
      PIN_NUMBER='(0,0,0,0,F7,0,0)';
      PINUSE='NC';
      NO_LOAD_CHECK='Both';
      NO_IO_CHECK='Both';
      NO_ASSERT_CHECK='TRUE';
      NO_DIR_CHECK='TRUE';
      ALLOW_CONNECT='TRUE';
    'NC'<32>:
      PIN_NUMBER='(0,0,0,0,F9,0,0)';
      PINUSE='NC';
      NO_LOAD_CHECK='Both';
      NO_IO_CHECK='Both';
      NO_ASSERT_CHECK='TRUE';
      NO_DIR_CHECK='TRUE';
      ALLOW_CONNECT='TRUE';
    'NC'<33>:
      PIN_NUMBER='(0,0,0,0,F10,0,0)';
      PINUSE='NC';
      NO_LOAD_CHECK='Both';
      NO_IO_CHECK='Both';
      NO_ASSERT_CHECK='TRUE';
      NO_DIR_CHECK='TRUE';
      ALLOW_CONNECT='TRUE';
    'NC'<34>:
      PIN_NUMBER='(0,0,0,0,F14,0,0)';
      PINUSE='NC';
      NO_LOAD_CHECK='Both';
      NO_IO_CHECK='Both';
      NO_ASSERT_CHECK='TRUE';
      NO_DIR_CHECK='TRUE';
      ALLOW_CONNECT='TRUE';
    'NC'<35>:
      PIN_NUMBER='(0,0,0,0,F19,0,0)';
      PINUSE='NC';
      NO_LOAD_CHECK='Both';
      NO_IO_CHECK='Both';
      NO_ASSERT_CHECK='TRUE';
      NO_DIR_CHECK='TRUE';
      ALLOW_CONNECT='TRUE';
    'NC'<36>:
      PIN_NUMBER='(0,0,0,0,F22,0,0)';
      PINUSE='NC';
      NO_LOAD_CHECK='Both';
      NO_IO_CHECK='Both';
      NO_ASSERT_CHECK='TRUE';
      NO_DIR_CHECK='TRUE';
      ALLOW_CONNECT='TRUE';
    'NC'<37>:
      PIN_NUMBER='(0,0,0,0,G3,0,0)';
      PINUSE='NC';
      NO_LOAD_CHECK='Both';
      NO_IO_CHECK='Both';
      NO_ASSERT_CHECK='TRUE';
      NO_DIR_CHECK='TRUE';
      ALLOW_CONNECT='TRUE';
    'NC'<38>:
      PIN_NUMBER='(0,0,0,0,G9,0,0)';
      PINUSE='NC';
      NO_LOAD_CHECK='Both';
      NO_IO_CHECK='Both';
      NO_ASSERT_CHECK='TRUE';
      NO_DIR_CHECK='TRUE';
      ALLOW_CONNECT='TRUE';
    'NC'<39>:
      PIN_NUMBER='(0,0,0,0,G10,0,0)';
      PINUSE='NC';
      NO_LOAD_CHECK='Both';
      NO_IO_CHECK='Both';
      NO_ASSERT_CHECK='TRUE';
      NO_DIR_CHECK='TRUE';
      ALLOW_CONNECT='TRUE';
    'NC'<40>:
      PIN_NUMBER='(0,0,0,0,G14,0,0)';
      PINUSE='NC';
      NO_LOAD_CHECK='Both';
      NO_IO_CHECK='Both';
      NO_ASSERT_CHECK='TRUE';
      NO_DIR_CHECK='TRUE';
      ALLOW_CONNECT='TRUE';
    'NC'<41>:
      PIN_NUMBER='(0,0,0,0,G19,0,0)';
      PINUSE='NC';
      NO_LOAD_CHECK='Both';
      NO_IO_CHECK='Both';
      NO_ASSERT_CHECK='TRUE';
      NO_DIR_CHECK='TRUE';
      ALLOW_CONNECT='TRUE';
    'NC'<42>:
      PIN_NUMBER='(0,0,0,0,G20,0,0)';
      PINUSE='NC';
      NO_LOAD_CHECK='Both';
      NO_IO_CHECK='Both';
      NO_ASSERT_CHECK='TRUE';
      NO_DIR_CHECK='TRUE';
      ALLOW_CONNECT='TRUE';
    'NC'<43>:
      PIN_NUMBER='(0,0,0,0,H18,0,0)';
      PINUSE='NC';
      NO_LOAD_CHECK='Both';
      NO_IO_CHECK='Both';
      NO_ASSERT_CHECK='TRUE';
      NO_DIR_CHECK='TRUE';
      ALLOW_CONNECT='TRUE';
    'NC'<44>:
      PIN_NUMBER='(0,0,0,0,H19,0,0)';
      PINUSE='NC';
      NO_LOAD_CHECK='Both';
      NO_IO_CHECK='Both';
      NO_ASSERT_CHECK='TRUE';
      NO_DIR_CHECK='TRUE';
      ALLOW_CONNECT='TRUE';
    'NC'<45>:
      PIN_NUMBER='(0,0,0,0,H22,0,0)';
      PINUSE='NC';
      NO_LOAD_CHECK='Both';
      NO_IO_CHECK='Both';
      NO_ASSERT_CHECK='TRUE';
      NO_DIR_CHECK='TRUE';
      ALLOW_CONNECT='TRUE';
    'NC'<46>:
      PIN_NUMBER='(0,0,0,0,J6,0,0)';
      PINUSE='NC';
      NO_LOAD_CHECK='Both';
      NO_IO_CHECK='Both';
      NO_ASSERT_CHECK='TRUE';
      NO_DIR_CHECK='TRUE';
      ALLOW_CONNECT='TRUE';
    'NC'<47>:
      PIN_NUMBER='(0,0,0,0,J7,0,0)';
      PINUSE='NC';
      NO_LOAD_CHECK='Both';
      NO_IO_CHECK='Both';
      NO_ASSERT_CHECK='TRUE';
      NO_DIR_CHECK='TRUE';
      ALLOW_CONNECT='TRUE';
    'NC'<48>:
      PIN_NUMBER='(0,0,0,0,J20,0,0)';
      PINUSE='NC';
      NO_LOAD_CHECK='Both';
      NO_IO_CHECK='Both';
      NO_ASSERT_CHECK='TRUE';
      NO_DIR_CHECK='TRUE';
      ALLOW_CONNECT='TRUE';
    'NC'<49>:
      PIN_NUMBER='(0,0,0,0,J21,0,0)';
      PINUSE='NC';
      NO_LOAD_CHECK='Both';
      NO_IO_CHECK='Both';
      NO_ASSERT_CHECK='TRUE';
      NO_DIR_CHECK='TRUE';
      ALLOW_CONNECT='TRUE';
    'NC'<50>:
      PIN_NUMBER='(0,0,0,0,K6,0,0)';
      PINUSE='NC';
      NO_LOAD_CHECK='Both';
      NO_IO_CHECK='Both';
      NO_ASSERT_CHECK='TRUE';
      NO_DIR_CHECK='TRUE';
      ALLOW_CONNECT='TRUE';
    'NC'<51>:
      PIN_NUMBER='(0,0,0,0,K7,0,0)';
      PINUSE='NC';
      NO_LOAD_CHECK='Both';
      NO_IO_CHECK='Both';
      NO_ASSERT_CHECK='TRUE';
      NO_DIR_CHECK='TRUE';
      ALLOW_CONNECT='TRUE';
    'NC'<52>:
      PIN_NUMBER='(0,0,0,0,K18,0,0)';
      PINUSE='NC';
      NO_LOAD_CHECK='Both';
      NO_IO_CHECK='Both';
      NO_ASSERT_CHECK='TRUE';
      NO_DIR_CHECK='TRUE';
      ALLOW_CONNECT='TRUE';
    'NC'<53>:
      PIN_NUMBER='(0,0,0,0,K20,0,0)';
      PINUSE='NC';
      NO_LOAD_CHECK='Both';
      NO_IO_CHECK='Both';
      NO_ASSERT_CHECK='TRUE';
      NO_DIR_CHECK='TRUE';
      ALLOW_CONNECT='TRUE';
    'NC'<54>:
      PIN_NUMBER='(0,0,0,0,L1,0,0)';
      PINUSE='NC';
      NO_LOAD_CHECK='Both';
      NO_IO_CHECK='Both';
      NO_ASSERT_CHECK='TRUE';
      NO_DIR_CHECK='TRUE';
      ALLOW_CONNECT='TRUE';
    'NC'<55>:
      PIN_NUMBER='(0,0,0,0,L2,0,0)';
      PINUSE='NC';
      NO_LOAD_CHECK='Both';
      NO_IO_CHECK='Both';
      NO_ASSERT_CHECK='TRUE';
      NO_DIR_CHECK='TRUE';
      ALLOW_CONNECT='TRUE';
    'NC'<56>:
      PIN_NUMBER='(0,0,0,0,L6,0,0)';
      PINUSE='NC';
      NO_LOAD_CHECK='Both';
      NO_IO_CHECK='Both';
      NO_ASSERT_CHECK='TRUE';
      NO_DIR_CHECK='TRUE';
      ALLOW_CONNECT='TRUE';
    'NC'<57>:
      PIN_NUMBER='(0,0,0,0,L7,0,0)';
      PINUSE='NC';
      NO_LOAD_CHECK='Both';
      NO_IO_CHECK='Both';
      NO_ASSERT_CHECK='TRUE';
      NO_DIR_CHECK='TRUE';
      ALLOW_CONNECT='TRUE';
    'NC'<58>:
      PIN_NUMBER='(0,0,0,0,L18,0,0)';
      PINUSE='NC';
      NO_LOAD_CHECK='Both';
      NO_IO_CHECK='Both';
      NO_ASSERT_CHECK='TRUE';
      NO_DIR_CHECK='TRUE';
      ALLOW_CONNECT='TRUE';
    'NC'<59>:
      PIN_NUMBER='(0,0,0,0,L19,0,0)';
      PINUSE='NC';
      NO_LOAD_CHECK='Both';
      NO_IO_CHECK='Both';
      NO_ASSERT_CHECK='TRUE';
      NO_DIR_CHECK='TRUE';
      ALLOW_CONNECT='TRUE';
    'NC'<60>:
      PIN_NUMBER='(0,0,0,0,L20,0,0)';
      PINUSE='NC';
      NO_LOAD_CHECK='Both';
      NO_IO_CHECK='Both';
      NO_ASSERT_CHECK='TRUE';
      NO_DIR_CHECK='TRUE';
      ALLOW_CONNECT='TRUE';
    'NC'<61>:
      PIN_NUMBER='(0,0,0,0,M4,0,0)';
      PINUSE='NC';
      NO_LOAD_CHECK='Both';
      NO_IO_CHECK='Both';
      NO_ASSERT_CHECK='TRUE';
      NO_DIR_CHECK='TRUE';
      ALLOW_CONNECT='TRUE';
    'NC'<62>:
      PIN_NUMBER='(0,0,0,0,M5,0,0)';
      PINUSE='NC';
      NO_LOAD_CHECK='Both';
      NO_IO_CHECK='Both';
      NO_ASSERT_CHECK='TRUE';
      NO_DIR_CHECK='TRUE';
      ALLOW_CONNECT='TRUE';
    'NC'<63>:
      PIN_NUMBER='(0,0,0,0,M16,0,0)';
      PINUSE='NC';
      NO_LOAD_CHECK='Both';
      NO_IO_CHECK='Both';
      NO_ASSERT_CHECK='TRUE';
      NO_DIR_CHECK='TRUE';
      ALLOW_CONNECT='TRUE';
    'NC'<64>:
      PIN_NUMBER='(0,0,0,0,M17,0,0)';
      PINUSE='NC';
      NO_LOAD_CHECK='Both';
      NO_IO_CHECK='Both';
      NO_ASSERT_CHECK='TRUE';
      NO_DIR_CHECK='TRUE';
      ALLOW_CONNECT='TRUE';
    'NC'<65>:
      PIN_NUMBER='(0,0,0,0,M21,0,0)';
      PINUSE='NC';
      NO_LOAD_CHECK='Both';
      NO_IO_CHECK='Both';
      NO_ASSERT_CHECK='TRUE';
      NO_DIR_CHECK='TRUE';
      ALLOW_CONNECT='TRUE';
    'NC'<66>:
      PIN_NUMBER='(0,0,0,0,M22,0,0)';
      PINUSE='NC';
      NO_LOAD_CHECK='Both';
      NO_IO_CHECK='Both';
      NO_ASSERT_CHECK='TRUE';
      NO_DIR_CHECK='TRUE';
      ALLOW_CONNECT='TRUE';
    'NC'<67>:
      PIN_NUMBER='(0,0,0,0,N3,0,0)';
      PINUSE='NC';
      NO_LOAD_CHECK='Both';
      NO_IO_CHECK='Both';
      NO_ASSERT_CHECK='TRUE';
      NO_DIR_CHECK='TRUE';
      ALLOW_CONNECT='TRUE';
    'NC'<68>:
      PIN_NUMBER='(0,0,0,0,N16,0,0)';
      PINUSE='NC';
      NO_LOAD_CHECK='Both';
      NO_IO_CHECK='Both';
      NO_ASSERT_CHECK='TRUE';
      NO_DIR_CHECK='TRUE';
      ALLOW_CONNECT='TRUE';
    'NC'<69>:
      PIN_NUMBER='(0,0,0,0,N17,0,0)';
      PINUSE='NC';
      NO_LOAD_CHECK='Both';
      NO_IO_CHECK='Both';
      NO_ASSERT_CHECK='TRUE';
      NO_DIR_CHECK='TRUE';
      ALLOW_CONNECT='TRUE';
    'NC'<70>:
      PIN_NUMBER='(0,0,0,0,P2,0,0)';
      PINUSE='NC';
      NO_LOAD_CHECK='Both';
      NO_IO_CHECK='Both';
      NO_ASSERT_CHECK='TRUE';
      NO_DIR_CHECK='TRUE';
      ALLOW_CONNECT='TRUE';
    'NC'<71>:
      PIN_NUMBER='(0,0,0,0,P4,0,0)';
      PINUSE='NC';
      NO_LOAD_CHECK='Both';
      NO_IO_CHECK='Both';
      NO_ASSERT_CHECK='TRUE';
      NO_DIR_CHECK='TRUE';
      ALLOW_CONNECT='TRUE';
    'NC'<72>:
      PIN_NUMBER='(0,0,0,0,P5,0,0)';
      PINUSE='NC';
      NO_LOAD_CHECK='Both';
      NO_IO_CHECK='Both';
      NO_ASSERT_CHECK='TRUE';
      NO_DIR_CHECK='TRUE';
      ALLOW_CONNECT='TRUE';
    'NC'<73>:
      PIN_NUMBER='(0,0,0,0,P16,0,0)';
      PINUSE='NC';
      NO_LOAD_CHECK='Both';
      NO_IO_CHECK='Both';
      NO_ASSERT_CHECK='TRUE';
      NO_DIR_CHECK='TRUE';
      ALLOW_CONNECT='TRUE';
    'NC'<74>:
      PIN_NUMBER='(0,0,0,0,P17,0,0)';
      PINUSE='NC';
      NO_LOAD_CHECK='Both';
      NO_IO_CHECK='Both';
      NO_ASSERT_CHECK='TRUE';
      NO_DIR_CHECK='TRUE';
      ALLOW_CONNECT='TRUE';
    'NC'<75>:
      PIN_NUMBER='(0,0,0,0,R4,0,0)';
      PINUSE='NC';
      NO_LOAD_CHECK='Both';
      NO_IO_CHECK='Both';
      NO_ASSERT_CHECK='TRUE';
      NO_DIR_CHECK='TRUE';
      ALLOW_CONNECT='TRUE';
    'NC'<76>:
      PIN_NUMBER='(0,0,0,0,R5,0,0)';
      PINUSE='NC';
      NO_LOAD_CHECK='Both';
      NO_IO_CHECK='Both';
      NO_ASSERT_CHECK='TRUE';
      NO_DIR_CHECK='TRUE';
      ALLOW_CONNECT='TRUE';
    'NC'<77>:
      PIN_NUMBER='(0,0,0,0,T1,0,0)';
      PINUSE='NC';
      NO_LOAD_CHECK='Both';
      NO_IO_CHECK='Both';
      NO_ASSERT_CHECK='TRUE';
      NO_DIR_CHECK='TRUE';
      ALLOW_CONNECT='TRUE';
    'NC'<78>:
      PIN_NUMBER='(0,0,0,0,T2,0,0)';
      PINUSE='NC';
      NO_LOAD_CHECK='Both';
      NO_IO_CHECK='Both';
      NO_ASSERT_CHECK='TRUE';
      NO_DIR_CHECK='TRUE';
      ALLOW_CONNECT='TRUE';
    'NC'<79>:
      PIN_NUMBER='(0,0,0,0,T3,0,0)';
      PINUSE='NC';
      NO_LOAD_CHECK='Both';
      NO_IO_CHECK='Both';
      NO_ASSERT_CHECK='TRUE';
      NO_DIR_CHECK='TRUE';
      ALLOW_CONNECT='TRUE';
    'NC'<80>:
      PIN_NUMBER='(0,0,0,0,T4,0,0)';
      PINUSE='NC';
      NO_LOAD_CHECK='Both';
      NO_IO_CHECK='Both';
      NO_ASSERT_CHECK='TRUE';
      NO_DIR_CHECK='TRUE';
      ALLOW_CONNECT='TRUE';
    'NC'<81>:
      PIN_NUMBER='(0,0,0,0,T9,0,0)';
      PINUSE='NC';
      NO_LOAD_CHECK='Both';
      NO_IO_CHECK='Both';
      NO_ASSERT_CHECK='TRUE';
      NO_DIR_CHECK='TRUE';
      ALLOW_CONNECT='TRUE';
    'NC'<82>:
      PIN_NUMBER='(0,0,0,0,T13,0,0)';
      PINUSE='NC';
      NO_LOAD_CHECK='Both';
      NO_IO_CHECK='Both';
      NO_ASSERT_CHECK='TRUE';
      NO_DIR_CHECK='TRUE';
      ALLOW_CONNECT='TRUE';
    'NC'<83>:
      PIN_NUMBER='(0,0,0,0,T14,0,0)';
      PINUSE='NC';
      NO_LOAD_CHECK='Both';
      NO_IO_CHECK='Both';
      NO_ASSERT_CHECK='TRUE';
      NO_DIR_CHECK='TRUE';
      ALLOW_CONNECT='TRUE';
    'NC'<84>:
      PIN_NUMBER='(0,0,0,0,T20,0,0)';
      PINUSE='NC';
      NO_LOAD_CHECK='Both';
      NO_IO_CHECK='Both';
      NO_ASSERT_CHECK='TRUE';
      NO_DIR_CHECK='TRUE';
      ALLOW_CONNECT='TRUE';
    'NC'<85>:
      PIN_NUMBER='(0,0,0,0,U1,0,0)';
      PINUSE='NC';
      NO_LOAD_CHECK='Both';
      NO_IO_CHECK='Both';
      NO_ASSERT_CHECK='TRUE';
      NO_DIR_CHECK='TRUE';
      ALLOW_CONNECT='TRUE';
    'NC'<86>:
      PIN_NUMBER='(0,0,0,0,U4,0,0)';
      PINUSE='NC';
      NO_LOAD_CHECK='Both';
      NO_IO_CHECK='Both';
      NO_ASSERT_CHECK='TRUE';
      NO_DIR_CHECK='TRUE';
      ALLOW_CONNECT='TRUE';
    'NC'<87>:
      PIN_NUMBER='(0,0,0,0,U9,0,0)';
      PINUSE='NC';
      NO_LOAD_CHECK='Both';
      NO_IO_CHECK='Both';
      NO_ASSERT_CHECK='TRUE';
      NO_DIR_CHECK='TRUE';
      ALLOW_CONNECT='TRUE';
    'NC'<88>:
      PIN_NUMBER='(0,0,0,0,U13,0,0)';
      PINUSE='NC';
      NO_LOAD_CHECK='Both';
      NO_IO_CHECK='Both';
      NO_ASSERT_CHECK='TRUE';
      NO_DIR_CHECK='TRUE';
      ALLOW_CONNECT='TRUE';
    'NC'<89>:
      PIN_NUMBER='(0,0,0,0,U14,0,0)';
      PINUSE='NC';
      NO_LOAD_CHECK='Both';
      NO_IO_CHECK='Both';
      NO_ASSERT_CHECK='TRUE';
      NO_DIR_CHECK='TRUE';
      ALLOW_CONNECT='TRUE';
    'NC'<90>:
      PIN_NUMBER='(0,0,0,0,U22,0,0)';
      PINUSE='NC';
      NO_LOAD_CHECK='Both';
      NO_IO_CHECK='Both';
      NO_ASSERT_CHECK='TRUE';
      NO_DIR_CHECK='TRUE';
      ALLOW_CONNECT='TRUE';
    'NC'<91>:
      PIN_NUMBER='(0,0,0,0,V2,0,0)';
      PINUSE='NC';
      NO_LOAD_CHECK='Both';
      NO_IO_CHECK='Both';
      NO_ASSERT_CHECK='TRUE';
      NO_DIR_CHECK='TRUE';
      ALLOW_CONNECT='TRUE';
    'NC'<92>:
      PIN_NUMBER='(0,0,0,0,V9,0,0)';
      PINUSE='NC';
      NO_LOAD_CHECK='Both';
      NO_IO_CHECK='Both';
      NO_ASSERT_CHECK='TRUE';
      NO_DIR_CHECK='TRUE';
      ALLOW_CONNECT='TRUE';
    'NC'<93>:
      PIN_NUMBER='(0,0,0,0,V10,0,0)';
      PINUSE='NC';
      NO_LOAD_CHECK='Both';
      NO_IO_CHECK='Both';
      NO_ASSERT_CHECK='TRUE';
      NO_DIR_CHECK='TRUE';
      ALLOW_CONNECT='TRUE';
    'NC'<94>:
      PIN_NUMBER='(0,0,0,0,V15,0,0)';
      PINUSE='NC';
      NO_LOAD_CHECK='Both';
      NO_IO_CHECK='Both';
      NO_ASSERT_CHECK='TRUE';
      NO_DIR_CHECK='TRUE';
      ALLOW_CONNECT='TRUE';
    'NC'<95>:
      PIN_NUMBER='(0,0,0,0,V20,0,0)';
      PINUSE='NC';
      NO_LOAD_CHECK='Both';
      NO_IO_CHECK='Both';
      NO_ASSERT_CHECK='TRUE';
      NO_DIR_CHECK='TRUE';
      ALLOW_CONNECT='TRUE';
    'NC'<96>:
      PIN_NUMBER='(0,0,0,0,W1,0,0)';
      PINUSE='NC';
      NO_LOAD_CHECK='Both';
      NO_IO_CHECK='Both';
      NO_ASSERT_CHECK='TRUE';
      NO_DIR_CHECK='TRUE';
      ALLOW_CONNECT='TRUE';
    'NC'<97>:
      PIN_NUMBER='(0,0,0,0,W9,0,0)';
      PINUSE='NC';
      NO_LOAD_CHECK='Both';
      NO_IO_CHECK='Both';
      NO_ASSERT_CHECK='TRUE';
      NO_DIR_CHECK='TRUE';
      ALLOW_CONNECT='TRUE';
    'NC'<98>:
      PIN_NUMBER='(0,0,0,0,W15,0,0)';
      PINUSE='NC';
      NO_LOAD_CHECK='Both';
      NO_IO_CHECK='Both';
      NO_ASSERT_CHECK='TRUE';
      NO_DIR_CHECK='TRUE';
      ALLOW_CONNECT='TRUE';
    'NC'<99>:
      PIN_NUMBER='(0,0,0,0,W21,0,0)';
      PINUSE='NC';
      NO_LOAD_CHECK='Both';
      NO_IO_CHECK='Both';
      NO_ASSERT_CHECK='TRUE';
      NO_DIR_CHECK='TRUE';
      ALLOW_CONNECT='TRUE';
    'NC'<100>:
      PIN_NUMBER='(0,0,0,0,Y6,0,0)';
      PINUSE='NC';
      NO_LOAD_CHECK='Both';
      NO_IO_CHECK='Both';
      NO_ASSERT_CHECK='TRUE';
      NO_DIR_CHECK='TRUE';
      ALLOW_CONNECT='TRUE';
    'NC'<101>:
      PIN_NUMBER='(0,0,0,0,Y9,0,0)';
      PINUSE='NC';
      NO_LOAD_CHECK='Both';
      NO_IO_CHECK='Both';
      NO_ASSERT_CHECK='TRUE';
      NO_DIR_CHECK='TRUE';
      ALLOW_CONNECT='TRUE';
    'NC'<102>:
      PIN_NUMBER='(0,0,0,0,Y11,0,0)';
      PINUSE='NC';
      NO_LOAD_CHECK='Both';
      NO_IO_CHECK='Both';
      NO_ASSERT_CHECK='TRUE';
      NO_DIR_CHECK='TRUE';
      ALLOW_CONNECT='TRUE';
    'NC'<103>:
      PIN_NUMBER='(0,0,0,0,Y15,0,0)';
      PINUSE='NC';
      NO_LOAD_CHECK='Both';
      NO_IO_CHECK='Both';
      NO_ASSERT_CHECK='TRUE';
      NO_DIR_CHECK='TRUE';
      ALLOW_CONNECT='TRUE';
    'NC'<104>:
      PIN_NUMBER='(0,0,0,0,Y18,0,0)';
      PINUSE='NC';
      NO_LOAD_CHECK='Both';
      NO_IO_CHECK='Both';
      NO_ASSERT_CHECK='TRUE';
      NO_DIR_CHECK='TRUE';
      ALLOW_CONNECT='TRUE';
    'GND'<0>:
      PIN_NUMBER='(0,0,0,0,0,A1,0)';
      PINUSE='GROUND';
      NO_LOAD_CHECK='Both';
      NO_IO_CHECK='Both';
      NO_ASSERT_CHECK='TRUE';
      NO_DIR_CHECK='TRUE';
      ALLOW_CONNECT='TRUE';
    'GND'<1>:
      PIN_NUMBER='(0,0,0,0,0,A9,0)';
      PINUSE='GROUND';
      NO_LOAD_CHECK='Both';
      NO_IO_CHECK='Both';
      NO_ASSERT_CHECK='TRUE';
      NO_DIR_CHECK='TRUE';
      ALLOW_CONNECT='TRUE';
    'GND'<2>:
      PIN_NUMBER='(0,0,0,0,0,A14,0)';
      PINUSE='GROUND';
      NO_LOAD_CHECK='Both';
      NO_IO_CHECK='Both';
      NO_ASSERT_CHECK='TRUE';
      NO_DIR_CHECK='TRUE';
      ALLOW_CONNECT='TRUE';
    'GND'<3>:
      PIN_NUMBER='(0,0,0,0,0,A22,0)';
      PINUSE='GROUND';
      NO_LOAD_CHECK='Both';
      NO_IO_CHECK='Both';
      NO_ASSERT_CHECK='TRUE';
      NO_DIR_CHECK='TRUE';
      ALLOW_CONNECT='TRUE';
    'GND'<4>:
      PIN_NUMBER='(0,0,0,0,0,AA2,0)';
      PINUSE='GROUND';
      NO_LOAD_CHECK='Both';
      NO_IO_CHECK='Both';
      NO_ASSERT_CHECK='TRUE';
      NO_DIR_CHECK='TRUE';
      ALLOW_CONNECT='TRUE';
    'GND'<5>:
      PIN_NUMBER='(0,0,0,0,0,AA21,0)';
      PINUSE='GROUND';
      NO_LOAD_CHECK='Both';
      NO_IO_CHECK='Both';
      NO_ASSERT_CHECK='TRUE';
      NO_DIR_CHECK='TRUE';
      ALLOW_CONNECT='TRUE';
    'GND'<6>:
      PIN_NUMBER='(0,0,0,0,0,AB1,0)';
      PINUSE='GROUND';
      NO_LOAD_CHECK='Both';
      NO_IO_CHECK='Both';
      NO_ASSERT_CHECK='TRUE';
      NO_DIR_CHECK='TRUE';
      ALLOW_CONNECT='TRUE';
    'GND'<7>:
      PIN_NUMBER='(0,0,0,0,0,AB9,0)';
      PINUSE='GROUND';
      NO_LOAD_CHECK='Both';
      NO_IO_CHECK='Both';
      NO_ASSERT_CHECK='TRUE';
      NO_DIR_CHECK='TRUE';
      ALLOW_CONNECT='TRUE';
    'GND'<8>:
      PIN_NUMBER='(0,0,0,0,0,AB14,0)';
      PINUSE='GROUND';
      NO_LOAD_CHECK='Both';
      NO_IO_CHECK='Both';
      NO_ASSERT_CHECK='TRUE';
      NO_DIR_CHECK='TRUE';
      ALLOW_CONNECT='TRUE';
    'GND'<9>:
      PIN_NUMBER='(0,0,0,0,0,AB22,0)';
      PINUSE='GROUND';
      NO_LOAD_CHECK='Both';
      NO_IO_CHECK='Both';
      NO_ASSERT_CHECK='TRUE';
      NO_DIR_CHECK='TRUE';
      ALLOW_CONNECT='TRUE';
    'GND'<10>:
      PIN_NUMBER='(0,0,0,0,0,B2,0)';
      PINUSE='GROUND';
      NO_LOAD_CHECK='Both';
      NO_IO_CHECK='Both';
      NO_ASSERT_CHECK='TRUE';
      NO_DIR_CHECK='TRUE';
      ALLOW_CONNECT='TRUE';
    'GND'<11>:
      PIN_NUMBER='(0,0,0,0,0,B21,0)';
      PINUSE='GROUND';
      NO_LOAD_CHECK='Both';
      NO_IO_CHECK='Both';
      NO_ASSERT_CHECK='TRUE';
      NO_DIR_CHECK='TRUE';
      ALLOW_CONNECT='TRUE';
    'GND'<12>:
      PIN_NUMBER='(0,0,0,0,0,E5,0)';
      PINUSE='GROUND';
      NO_LOAD_CHECK='Both';
      NO_IO_CHECK='Both';
      NO_ASSERT_CHECK='TRUE';
      NO_DIR_CHECK='TRUE';
      ALLOW_CONNECT='TRUE';
    'GND'<13>:
      PIN_NUMBER='(0,0,0,0,0,E18,0)';
      PINUSE='GROUND';
      NO_LOAD_CHECK='Both';
      NO_IO_CHECK='Both';
      NO_ASSERT_CHECK='TRUE';
      NO_DIR_CHECK='TRUE';
      ALLOW_CONNECT='TRUE';
    'GND'<14>:
      PIN_NUMBER='(0,0,0,0,0,H8,0)';
      PINUSE='GROUND';
      NO_LOAD_CHECK='Both';
      NO_IO_CHECK='Both';
      NO_ASSERT_CHECK='TRUE';
      NO_DIR_CHECK='TRUE';
      ALLOW_CONNECT='TRUE';
    'GND'<15>:
      PIN_NUMBER='(0,0,0,0,0,H15,0)';
      PINUSE='GROUND';
      NO_LOAD_CHECK='Both';
      NO_IO_CHECK='Both';
      NO_ASSERT_CHECK='TRUE';
      NO_DIR_CHECK='TRUE';
      ALLOW_CONNECT='TRUE';
    'GND'<16>:
      PIN_NUMBER='(0,0,0,0,0,J1,0)';
      PINUSE='GROUND';
      NO_LOAD_CHECK='Both';
      NO_IO_CHECK='Both';
      NO_ASSERT_CHECK='TRUE';
      NO_DIR_CHECK='TRUE';
      ALLOW_CONNECT='TRUE';
    'GND'<17>:
      PIN_NUMBER='(0,0,0,0,0,J9,0)';
      PINUSE='GROUND';
      NO_LOAD_CHECK='Both';
      NO_IO_CHECK='Both';
      NO_ASSERT_CHECK='TRUE';
      NO_DIR_CHECK='TRUE';
      ALLOW_CONNECT='TRUE';
    'GND'<18>:
      PIN_NUMBER='(0,0,0,0,0,J10,0)';
      PINUSE='GROUND';
      NO_LOAD_CHECK='Both';
      NO_IO_CHECK='Both';
      NO_ASSERT_CHECK='TRUE';
      NO_DIR_CHECK='TRUE';
      ALLOW_CONNECT='TRUE';
    'GND'<19>:
      PIN_NUMBER='(0,0,0,0,0,J11,0)';
      PINUSE='GROUND';
      NO_LOAD_CHECK='Both';
      NO_IO_CHECK='Both';
      NO_ASSERT_CHECK='TRUE';
      NO_DIR_CHECK='TRUE';
      ALLOW_CONNECT='TRUE';
    'GND'<20>:
      PIN_NUMBER='(0,0,0,0,0,J12,0)';
      PINUSE='GROUND';
      NO_LOAD_CHECK='Both';
      NO_IO_CHECK='Both';
      NO_ASSERT_CHECK='TRUE';
      NO_DIR_CHECK='TRUE';
      ALLOW_CONNECT='TRUE';
    'GND'<21>:
      PIN_NUMBER='(0,0,0,0,0,J13,0)';
      PINUSE='GROUND';
      NO_LOAD_CHECK='Both';
      NO_IO_CHECK='Both';
      NO_ASSERT_CHECK='TRUE';
      NO_DIR_CHECK='TRUE';
      ALLOW_CONNECT='TRUE';
    'GND'<22>:
      PIN_NUMBER='(0,0,0,0,0,J14,0)';
      PINUSE='GROUND';
      NO_LOAD_CHECK='Both';
      NO_IO_CHECK='Both';
      NO_ASSERT_CHECK='TRUE';
      NO_DIR_CHECK='TRUE';
      ALLOW_CONNECT='TRUE';
    'GND'<23>:
      PIN_NUMBER='(0,0,0,0,0,J22,0)';
      PINUSE='GROUND';
      NO_LOAD_CHECK='Both';
      NO_IO_CHECK='Both';
      NO_ASSERT_CHECK='TRUE';
      NO_DIR_CHECK='TRUE';
      ALLOW_CONNECT='TRUE';
    'GND'<24>:
      PIN_NUMBER='(0,0,0,0,0,K9,0)';
      PINUSE='GROUND';
      NO_LOAD_CHECK='Both';
      NO_IO_CHECK='Both';
      NO_ASSERT_CHECK='TRUE';
      NO_DIR_CHECK='TRUE';
      ALLOW_CONNECT='TRUE';
    'GND'<25>:
      PIN_NUMBER='(0,0,0,0,0,K14,0)';
      PINUSE='GROUND';
      NO_LOAD_CHECK='Both';
      NO_IO_CHECK='Both';
      NO_ASSERT_CHECK='TRUE';
      NO_DIR_CHECK='TRUE';
      ALLOW_CONNECT='TRUE';
    'GND'<26>:
      PIN_NUMBER='(0,0,0,0,0,L9,0)';
      PINUSE='GROUND';
      NO_LOAD_CHECK='Both';
      NO_IO_CHECK='Both';
      NO_ASSERT_CHECK='TRUE';
      NO_DIR_CHECK='TRUE';
      ALLOW_CONNECT='TRUE';
    'GND'<27>:
      PIN_NUMBER='(0,0,0,0,0,L11,0)';
      PINUSE='GROUND';
      NO_LOAD_CHECK='Both';
      NO_IO_CHECK='Both';
      NO_ASSERT_CHECK='TRUE';
      NO_DIR_CHECK='TRUE';
      ALLOW_CONNECT='TRUE';
    'GND'<28>:
      PIN_NUMBER='(0,0,0,0,0,L12,0)';
      PINUSE='GROUND';
      NO_LOAD_CHECK='Both';
      NO_IO_CHECK='Both';
      NO_ASSERT_CHECK='TRUE';
      NO_DIR_CHECK='TRUE';
      ALLOW_CONNECT='TRUE';
    'GND'<29>:
      PIN_NUMBER='(0,0,0,0,0,L14,0)';
      PINUSE='GROUND';
      NO_LOAD_CHECK='Both';
      NO_IO_CHECK='Both';
      NO_ASSERT_CHECK='TRUE';
      NO_DIR_CHECK='TRUE';
      ALLOW_CONNECT='TRUE';
    'GND'<30>:
      PIN_NUMBER='(0,0,0,0,0,M9,0)';
      PINUSE='GROUND';
      NO_LOAD_CHECK='Both';
      NO_IO_CHECK='Both';
      NO_ASSERT_CHECK='TRUE';
      NO_DIR_CHECK='TRUE';
      ALLOW_CONNECT='TRUE';
    'GND'<31>:
      PIN_NUMBER='(0,0,0,0,0,M11,0)';
      PINUSE='GROUND';
      NO_LOAD_CHECK='Both';
      NO_IO_CHECK='Both';
      NO_ASSERT_CHECK='TRUE';
      NO_DIR_CHECK='TRUE';
      ALLOW_CONNECT='TRUE';
    'GND'<32>:
      PIN_NUMBER='(0,0,0,0,0,M12,0)';
      PINUSE='GROUND';
      NO_LOAD_CHECK='Both';
      NO_IO_CHECK='Both';
      NO_ASSERT_CHECK='TRUE';
      NO_DIR_CHECK='TRUE';
      ALLOW_CONNECT='TRUE';
    'GND'<33>:
      PIN_NUMBER='(0,0,0,0,0,M14,0)';
      PINUSE='GROUND';
      NO_LOAD_CHECK='Both';
      NO_IO_CHECK='Both';
      NO_ASSERT_CHECK='TRUE';
      NO_DIR_CHECK='TRUE';
      ALLOW_CONNECT='TRUE';
    'GND'<34>:
      PIN_NUMBER='(0,0,0,0,0,N9,0)';
      PINUSE='GROUND';
      NO_LOAD_CHECK='Both';
      NO_IO_CHECK='Both';
      NO_ASSERT_CHECK='TRUE';
      NO_DIR_CHECK='TRUE';
      ALLOW_CONNECT='TRUE';
    'GND'<35>:
      PIN_NUMBER='(0,0,0,0,0,N14,0)';
      PINUSE='GROUND';
      NO_LOAD_CHECK='Both';
      NO_IO_CHECK='Both';
      NO_ASSERT_CHECK='TRUE';
      NO_DIR_CHECK='TRUE';
      ALLOW_CONNECT='TRUE';
    'GND'<36>:
      PIN_NUMBER='(0,0,0,0,0,P1,0)';
      PINUSE='GROUND';
      NO_LOAD_CHECK='Both';
      NO_IO_CHECK='Both';
      NO_ASSERT_CHECK='TRUE';
      NO_DIR_CHECK='TRUE';
      ALLOW_CONNECT='TRUE';
    'GND'<37>:
      PIN_NUMBER='(0,0,0,0,0,P9,0)';
      PINUSE='GROUND';
      NO_LOAD_CHECK='Both';
      NO_IO_CHECK='Both';
      NO_ASSERT_CHECK='TRUE';
      NO_DIR_CHECK='TRUE';
      ALLOW_CONNECT='TRUE';
    'GND'<38>:
      PIN_NUMBER='(0,0,0,0,0,P10,0)';
      PINUSE='GROUND';
      NO_LOAD_CHECK='Both';
      NO_IO_CHECK='Both';
      NO_ASSERT_CHECK='TRUE';
      NO_DIR_CHECK='TRUE';
      ALLOW_CONNECT='TRUE';
    'GND'<39>:
      PIN_NUMBER='(0,0,0,0,0,P11,0)';
      PINUSE='GROUND';
      NO_LOAD_CHECK='Both';
      NO_IO_CHECK='Both';
      NO_ASSERT_CHECK='TRUE';
      NO_DIR_CHECK='TRUE';
      ALLOW_CONNECT='TRUE';
    'GND'<40>:
      PIN_NUMBER='(0,0,0,0,0,P12,0)';
      PINUSE='GROUND';
      NO_LOAD_CHECK='Both';
      NO_IO_CHECK='Both';
      NO_ASSERT_CHECK='TRUE';
      NO_DIR_CHECK='TRUE';
      ALLOW_CONNECT='TRUE';
    'GND'<41>:
      PIN_NUMBER='(0,0,0,0,0,P13,0)';
      PINUSE='GROUND';
      NO_LOAD_CHECK='Both';
      NO_IO_CHECK='Both';
      NO_ASSERT_CHECK='TRUE';
      NO_DIR_CHECK='TRUE';
      ALLOW_CONNECT='TRUE';
    'GND'<42>:
      PIN_NUMBER='(0,0,0,0,0,P14,0)';
      PINUSE='GROUND';
      NO_LOAD_CHECK='Both';
      NO_IO_CHECK='Both';
      NO_ASSERT_CHECK='TRUE';
      NO_DIR_CHECK='TRUE';
      ALLOW_CONNECT='TRUE';
    'GND'<43>:
      PIN_NUMBER='(0,0,0,0,0,P22,0)';
      PINUSE='GROUND';
      NO_LOAD_CHECK='Both';
      NO_IO_CHECK='Both';
      NO_ASSERT_CHECK='TRUE';
      NO_DIR_CHECK='TRUE';
      ALLOW_CONNECT='TRUE';
    'GND'<44>:
      PIN_NUMBER='(0,0,0,0,0,R8,0)';
      PINUSE='GROUND';
      NO_LOAD_CHECK='Both';
      NO_IO_CHECK='Both';
      NO_ASSERT_CHECK='TRUE';
      NO_DIR_CHECK='TRUE';
      ALLOW_CONNECT='TRUE';
    'GND'<45>:
      PIN_NUMBER='(0,0,0,0,0,R15,0)';
      PINUSE='GROUND';
      NO_LOAD_CHECK='Both';
      NO_IO_CHECK='Both';
      NO_ASSERT_CHECK='TRUE';
      NO_DIR_CHECK='TRUE';
      ALLOW_CONNECT='TRUE';
    'GND'<46>:
      PIN_NUMBER='(0,0,0,0,0,V5,0)';
      PINUSE='GROUND';
      NO_LOAD_CHECK='Both';
      NO_IO_CHECK='Both';
      NO_ASSERT_CHECK='TRUE';
      NO_DIR_CHECK='TRUE';
      ALLOW_CONNECT='TRUE';
    'GND'<47>:
      PIN_NUMBER='(0,0,0,0,0,V18,0)';
      PINUSE='GROUND';
      NO_LOAD_CHECK='Both';
      NO_IO_CHECK='Both';
      NO_ASSERT_CHECK='TRUE';
      NO_DIR_CHECK='TRUE';
      ALLOW_CONNECT='TRUE';
    'VCCIO2'<0>:
      PIN_NUMBER='(0,0,0,0,0,0,AA6)';
      PINUSE='POWER';
      NO_LOAD_CHECK='Both';
      NO_IO_CHECK='Both';
      NO_ASSERT_CHECK='TRUE';
      NO_DIR_CHECK='TRUE';
      ALLOW_CONNECT='TRUE';
    'VCCIO2'<1>:
      PIN_NUMBER='(0,0,0,0,0,0,AA17)';
      PINUSE='POWER';
      NO_LOAD_CHECK='Both';
      NO_IO_CHECK='Both';
      NO_ASSERT_CHECK='TRUE';
      NO_DIR_CHECK='TRUE';
      ALLOW_CONNECT='TRUE';
    'VCCIO0'<0>:
      PIN_NUMBER='(0,0,0,0,0,0,B6)';
      PINUSE='POWER';
      NO_LOAD_CHECK='Both';
      NO_IO_CHECK='Both';
      NO_ASSERT_CHECK='TRUE';
      NO_DIR_CHECK='TRUE';
      ALLOW_CONNECT='TRUE';
    'VCCIO0'<1>:
      PIN_NUMBER='(0,0,0,0,0,0,B17)';
      PINUSE='POWER';
      NO_LOAD_CHECK='Both';
      NO_IO_CHECK='Both';
      NO_ASSERT_CHECK='TRUE';
      NO_DIR_CHECK='TRUE';
      ALLOW_CONNECT='TRUE';
    'VCCIO0'<2>:
      PIN_NUMBER='(0,0,0,0,0,0,D10)';
      PINUSE='POWER';
      NO_LOAD_CHECK='Both';
      NO_IO_CHECK='Both';
      NO_ASSERT_CHECK='TRUE';
      NO_DIR_CHECK='TRUE';
      ALLOW_CONNECT='TRUE';
    'VCCIO0'<3>:
      PIN_NUMBER='(0,0,0,0,0,0,D13)';
      PINUSE='POWER';
      NO_LOAD_CHECK='Both';
      NO_IO_CHECK='Both';
      NO_ASSERT_CHECK='TRUE';
      NO_DIR_CHECK='TRUE';
      ALLOW_CONNECT='TRUE';
    'VCCIO5'<0>:
      PIN_NUMBER='(0,0,0,0,0,0,F2)';
      PINUSE='POWER';
      NO_LOAD_CHECK='Both';
      NO_IO_CHECK='Both';
      NO_ASSERT_CHECK='TRUE';
      NO_DIR_CHECK='TRUE';
      ALLOW_CONNECT='TRUE';
    'VCCIO1'<0>:
      PIN_NUMBER='(0,0,0,0,0,0,F21)';
      PINUSE='POWER';
      NO_LOAD_CHECK='Both';
      NO_IO_CHECK='Both';
      NO_ASSERT_CHECK='TRUE';
      NO_DIR_CHECK='TRUE';
      ALLOW_CONNECT='TRUE';
    'VCCIO0'<4>:
      PIN_NUMBER='(0,0,0,0,0,0,H9)';
      PINUSE='POWER';
      NO_LOAD_CHECK='Both';
      NO_IO_CHECK='Both';
      NO_ASSERT_CHECK='TRUE';
      NO_DIR_CHECK='TRUE';
      ALLOW_CONNECT='TRUE';
    'VCCIO0'<5>:
      PIN_NUMBER='(0,0,0,0,0,0,H10)';
      PINUSE='POWER';
      NO_LOAD_CHECK='Both';
      NO_IO_CHECK='Both';
      NO_ASSERT_CHECK='TRUE';
      NO_DIR_CHECK='TRUE';
      ALLOW_CONNECT='TRUE';
    'VCCIO0'<6>:
      PIN_NUMBER='(0,0,0,0,0,0,H11)';
      PINUSE='POWER';
      NO_LOAD_CHECK='Both';
      NO_IO_CHECK='Both';
      NO_ASSERT_CHECK='TRUE';
      NO_DIR_CHECK='TRUE';
      ALLOW_CONNECT='TRUE';
    'VCCIO0'<7>:
      PIN_NUMBER='(0,0,0,0,0,0,H12)';
      PINUSE='POWER';
      NO_LOAD_CHECK='Both';
      NO_IO_CHECK='Both';
      NO_ASSERT_CHECK='TRUE';
      NO_DIR_CHECK='TRUE';
      ALLOW_CONNECT='TRUE';
    'VCCIO0'<8>:
      PIN_NUMBER='(0,0,0,0,0,0,H13)';
      PINUSE='POWER';
      NO_LOAD_CHECK='Both';
      NO_IO_CHECK='Both';
      NO_ASSERT_CHECK='TRUE';
      NO_DIR_CHECK='TRUE';
      ALLOW_CONNECT='TRUE';
    'VCCIO0'<9>:
      PIN_NUMBER='(0,0,0,0,0,0,H14)';
      PINUSE='POWER';
      NO_LOAD_CHECK='Both';
      NO_IO_CHECK='Both';
      NO_ASSERT_CHECK='TRUE';
      NO_DIR_CHECK='TRUE';
      ALLOW_CONNECT='TRUE';
    'VCCIO5'<1>:
      PIN_NUMBER='(0,0,0,0,0,0,J8)';
      PINUSE='POWER';
      NO_LOAD_CHECK='Both';
      NO_IO_CHECK='Both';
      NO_ASSERT_CHECK='TRUE';
      NO_DIR_CHECK='TRUE';
      ALLOW_CONNECT='TRUE';
    'VCCIO1'<1>:
      PIN_NUMBER='(0,0,0,0,0,0,J15)';
      PINUSE='POWER';
      NO_LOAD_CHECK='Both';
      NO_IO_CHECK='Both';
      NO_ASSERT_CHECK='TRUE';
      NO_DIR_CHECK='TRUE';
      ALLOW_CONNECT='TRUE';
    'VCCIO4'<0>:
      PIN_NUMBER='(0,0,0,0,0,0,K4)';
      PINUSE='POWER';
      NO_LOAD_CHECK='Both';
      NO_IO_CHECK='Both';
      NO_ASSERT_CHECK='TRUE';
      NO_DIR_CHECK='TRUE';
      ALLOW_CONNECT='TRUE';
    'VCCIO5'<2>:
      PIN_NUMBER='(0,0,0,0,0,0,K8)';
      PINUSE='POWER';
      NO_LOAD_CHECK='Both';
      NO_IO_CHECK='Both';
      NO_ASSERT_CHECK='TRUE';
      NO_DIR_CHECK='TRUE';
      ALLOW_CONNECT='TRUE';
    'VCC'<0>:
      PIN_NUMBER='(0,0,0,0,0,0,K10)';
      PINUSE='POWER';
      NO_LOAD_CHECK='Both';
      NO_IO_CHECK='Both';
      NO_ASSERT_CHECK='TRUE';
      NO_DIR_CHECK='TRUE';
      ALLOW_CONNECT='TRUE';
    'VCC'<1>:
      PIN_NUMBER='(0,0,0,0,0,0,K11)';
      PINUSE='POWER';
      NO_LOAD_CHECK='Both';
      NO_IO_CHECK='Both';
      NO_ASSERT_CHECK='TRUE';
      NO_DIR_CHECK='TRUE';
      ALLOW_CONNECT='TRUE';
    'VCC'<2>:
      PIN_NUMBER='(0,0,0,0,0,0,K12)';
      PINUSE='POWER';
      NO_LOAD_CHECK='Both';
      NO_IO_CHECK='Both';
      NO_ASSERT_CHECK='TRUE';
      NO_DIR_CHECK='TRUE';
      ALLOW_CONNECT='TRUE';
    'VCC'<3>:
      PIN_NUMBER='(0,0,0,0,0,0,K13)';
      PINUSE='POWER';
      NO_LOAD_CHECK='Both';
      NO_IO_CHECK='Both';
      NO_ASSERT_CHECK='TRUE';
      NO_DIR_CHECK='TRUE';
      ALLOW_CONNECT='TRUE';
    'VCCIO1'<2>:
      PIN_NUMBER='(0,0,0,0,0,0,K15)';
      PINUSE='POWER';
      NO_LOAD_CHECK='Both';
      NO_IO_CHECK='Both';
      NO_ASSERT_CHECK='TRUE';
      NO_DIR_CHECK='TRUE';
      ALLOW_CONNECT='TRUE';
    'VCCIO1'<3>:
      PIN_NUMBER='(0,0,0,0,0,0,K19)';
      PINUSE='POWER';
      NO_LOAD_CHECK='Both';
      NO_IO_CHECK='Both';
      NO_ASSERT_CHECK='TRUE';
      NO_DIR_CHECK='TRUE';
      ALLOW_CONNECT='TRUE';
    'VCCIO4'<1>:
      PIN_NUMBER='(0,0,0,0,0,0,L8)';
      PINUSE='POWER';
      NO_LOAD_CHECK='Both';
      NO_IO_CHECK='Both';
      NO_ASSERT_CHECK='TRUE';
      NO_DIR_CHECK='TRUE';
      ALLOW_CONNECT='TRUE';
    'VCC'<4>:
      PIN_NUMBER='(0,0,0,0,0,0,L10)';
      PINUSE='POWER';
      NO_LOAD_CHECK='Both';
      NO_IO_CHECK='Both';
      NO_ASSERT_CHECK='TRUE';
      NO_DIR_CHECK='TRUE';
      ALLOW_CONNECT='TRUE';
    'VCC'<5>:
      PIN_NUMBER='(0,0,0,0,0,0,L13)';
      PINUSE='POWER';
      NO_LOAD_CHECK='Both';
      NO_IO_CHECK='Both';
      NO_ASSERT_CHECK='TRUE';
      NO_DIR_CHECK='TRUE';
      ALLOW_CONNECT='TRUE';
    'VCCIO1'<4>:
      PIN_NUMBER='(0,0,0,0,0,0,L15)';
      PINUSE='POWER';
      NO_LOAD_CHECK='Both';
      NO_IO_CHECK='Both';
      NO_ASSERT_CHECK='TRUE';
      NO_DIR_CHECK='TRUE';
      ALLOW_CONNECT='TRUE';
    'VCCIO4'<2>:
      PIN_NUMBER='(0,0,0,0,0,0,M8)';
      PINUSE='POWER';
      NO_LOAD_CHECK='Both';
      NO_IO_CHECK='Both';
      NO_ASSERT_CHECK='TRUE';
      NO_DIR_CHECK='TRUE';
      ALLOW_CONNECT='TRUE';
    'VCC'<6>:
      PIN_NUMBER='(0,0,0,0,0,0,M10)';
      PINUSE='POWER';
      NO_LOAD_CHECK='Both';
      NO_IO_CHECK='Both';
      NO_ASSERT_CHECK='TRUE';
      NO_DIR_CHECK='TRUE';
      ALLOW_CONNECT='TRUE';
    'VCC'<7>:
      PIN_NUMBER='(0,0,0,0,0,0,M13)';
      PINUSE='POWER';
      NO_LOAD_CHECK='Both';
      NO_IO_CHECK='Both';
      NO_ASSERT_CHECK='TRUE';
      NO_DIR_CHECK='TRUE';
      ALLOW_CONNECT='TRUE';
    'VCCIO1'<5>:
      PIN_NUMBER='(0,0,0,0,0,0,M15)';
      PINUSE='POWER';
      NO_LOAD_CHECK='Both';
      NO_IO_CHECK='Both';
      NO_ASSERT_CHECK='TRUE';
      NO_DIR_CHECK='TRUE';
      ALLOW_CONNECT='TRUE';
    'VCCIO4'<3>:
      PIN_NUMBER='(0,0,0,0,0,0,N4)';
      PINUSE='POWER';
      NO_LOAD_CHECK='Both';
      NO_IO_CHECK='Both';
      NO_ASSERT_CHECK='TRUE';
      NO_DIR_CHECK='TRUE';
      ALLOW_CONNECT='TRUE';
    'VCCIO3'<0>:
      PIN_NUMBER='(0,0,0,0,0,0,N8)';
      PINUSE='POWER';
      NO_LOAD_CHECK='Both';
      NO_IO_CHECK='Both';
      NO_ASSERT_CHECK='TRUE';
      NO_DIR_CHECK='TRUE';
      ALLOW_CONNECT='TRUE';
    'VCC'<8>:
      PIN_NUMBER='(0,0,0,0,0,0,N10)';
      PINUSE='POWER';
      NO_LOAD_CHECK='Both';
      NO_IO_CHECK='Both';
      NO_ASSERT_CHECK='TRUE';
      NO_DIR_CHECK='TRUE';
      ALLOW_CONNECT='TRUE';
    'VCC'<9>:
      PIN_NUMBER='(0,0,0,0,0,0,N11)';
      PINUSE='POWER';
      NO_LOAD_CHECK='Both';
      NO_IO_CHECK='Both';
      NO_ASSERT_CHECK='TRUE';
      NO_DIR_CHECK='TRUE';
      ALLOW_CONNECT='TRUE';
    'VCC'<10>:
      PIN_NUMBER='(0,0,0,0,0,0,N12)';
      PINUSE='POWER';
      NO_LOAD_CHECK='Both';
      NO_IO_CHECK='Both';
      NO_ASSERT_CHECK='TRUE';
      NO_DIR_CHECK='TRUE';
      ALLOW_CONNECT='TRUE';
    'VCC'<11>:
      PIN_NUMBER='(0,0,0,0,0,0,N13)';
      PINUSE='POWER';
      NO_LOAD_CHECK='Both';
      NO_IO_CHECK='Both';
      NO_ASSERT_CHECK='TRUE';
      NO_DIR_CHECK='TRUE';
      ALLOW_CONNECT='TRUE';
    'VCCIO1'<6>:
      PIN_NUMBER='(0,0,0,0,0,0,N15)';
      PINUSE='POWER';
      NO_LOAD_CHECK='Both';
      NO_IO_CHECK='Both';
      NO_ASSERT_CHECK='TRUE';
      NO_DIR_CHECK='TRUE';
      ALLOW_CONNECT='TRUE';
    'VCCIO1'<7>:
      PIN_NUMBER='(0,0,0,0,0,0,N19)';
      PINUSE='POWER';
      NO_LOAD_CHECK='Both';
      NO_IO_CHECK='Both';
      NO_ASSERT_CHECK='TRUE';
      NO_DIR_CHECK='TRUE';
      ALLOW_CONNECT='TRUE';
    'VCCIO3'<1>:
      PIN_NUMBER='(0,0,0,0,0,0,P8)';
      PINUSE='POWER';
      NO_LOAD_CHECK='Both';
      NO_IO_CHECK='Both';
      NO_ASSERT_CHECK='TRUE';
      NO_DIR_CHECK='TRUE';
      ALLOW_CONNECT='TRUE';
    'VCCIO1'<8>:
      PIN_NUMBER='(0,0,0,0,0,0,P15)';
      PINUSE='POWER';
      NO_LOAD_CHECK='Both';
      NO_IO_CHECK='Both';
      NO_ASSERT_CHECK='TRUE';
      NO_DIR_CHECK='TRUE';
      ALLOW_CONNECT='TRUE';
    'VCCIO2'<2>:
      PIN_NUMBER='(0,0,0,0,0,0,R9)';
      PINUSE='POWER';
      NO_LOAD_CHECK='Both';
      NO_IO_CHECK='Both';
      NO_ASSERT_CHECK='TRUE';
      NO_DIR_CHECK='TRUE';
      ALLOW_CONNECT='TRUE';
    'VCCIO2'<3>:
      PIN_NUMBER='(0,0,0,0,0,0,R10)';
      PINUSE='POWER';
      NO_LOAD_CHECK='Both';
      NO_IO_CHECK='Both';
      NO_ASSERT_CHECK='TRUE';
      NO_DIR_CHECK='TRUE';
      ALLOW_CONNECT='TRUE';
    'VCCIO2'<4>:
      PIN_NUMBER='(0,0,0,0,0,0,R11)';
      PINUSE='POWER';
      NO_LOAD_CHECK='Both';
      NO_IO_CHECK='Both';
      NO_ASSERT_CHECK='TRUE';
      NO_DIR_CHECK='TRUE';
      ALLOW_CONNECT='TRUE';
    'VCCIO2'<5>:
      PIN_NUMBER='(0,0,0,0,0,0,R12)';
      PINUSE='POWER';
      NO_LOAD_CHECK='Both';
      NO_IO_CHECK='Both';
      NO_ASSERT_CHECK='TRUE';
      NO_DIR_CHECK='TRUE';
      ALLOW_CONNECT='TRUE';
    'VCCIO2'<6>:
      PIN_NUMBER='(0,0,0,0,0,0,R13)';
      PINUSE='POWER';
      NO_LOAD_CHECK='Both';
      NO_IO_CHECK='Both';
      NO_ASSERT_CHECK='TRUE';
      NO_DIR_CHECK='TRUE';
      ALLOW_CONNECT='TRUE';
    'VCCIO2'<7>:
      PIN_NUMBER='(0,0,0,0,0,0,R14)';
      PINUSE='POWER';
      NO_LOAD_CHECK='Both';
      NO_IO_CHECK='Both';
      NO_ASSERT_CHECK='TRUE';
      NO_DIR_CHECK='TRUE';
      ALLOW_CONNECT='TRUE';
    'VCCIO3'<2>:
      PIN_NUMBER='(0,0,0,0,0,0,U2)';
      PINUSE='POWER';
      NO_LOAD_CHECK='Both';
      NO_IO_CHECK='Both';
      NO_ASSERT_CHECK='TRUE';
      NO_DIR_CHECK='TRUE';
      ALLOW_CONNECT='TRUE';
    'VCCIO1'<9>:
      PIN_NUMBER='(0,0,0,0,0,0,U21)';
      PINUSE='POWER';
      NO_LOAD_CHECK='Both';
      NO_IO_CHECK='Both';
      NO_ASSERT_CHECK='TRUE';
      NO_DIR_CHECK='TRUE';
      ALLOW_CONNECT='TRUE';
    'VCCIO2'<8>:
      PIN_NUMBER='(0,0,0,0,0,0,W10)';
      PINUSE='POWER';
      NO_LOAD_CHECK='Both';
      NO_IO_CHECK='Both';
      NO_ASSERT_CHECK='TRUE';
      NO_DIR_CHECK='TRUE';
      ALLOW_CONNECT='TRUE';
    'VCCIO2'<9>:
      PIN_NUMBER='(0,0,0,0,0,0,W13)';
      PINUSE='POWER';
      NO_LOAD_CHECK='Both';
      NO_IO_CHECK='Both';
      NO_ASSERT_CHECK='TRUE';
      NO_DIR_CHECK='TRUE';
      ALLOW_CONNECT='TRUE';
  end_pin;
  body
    PART_NAME='LCMXO2_A';
    PHYS_DES_PREFIX='U';
  end_body;
end_primitive;
primitive 'LCMXO2_A_484BGA2';
  pin
    'GND'<47>:
      PIN_NUMBER='(0,0,0,0,0,0,AB22)';
      PINUSE='GROUND';
      NO_LOAD_CHECK='Both';
      NO_IO_CHECK='Both';
      NO_ASSERT_CHECK='TRUE';
      NO_DIR_CHECK='TRUE';
      ALLOW_CONNECT='TRUE';
    'GND'<46>:
      PIN_NUMBER='(0,0,0,0,0,0,AB14)';
      PINUSE='GROUND';
      NO_LOAD_CHECK='Both';
      NO_IO_CHECK='Both';
      NO_ASSERT_CHECK='TRUE';
      NO_DIR_CHECK='TRUE';
      ALLOW_CONNECT='TRUE';
    'GND'<45>:
      PIN_NUMBER='(0,0,0,0,0,0,AB9)';
      PINUSE='GROUND';
      NO_LOAD_CHECK='Both';
      NO_IO_CHECK='Both';
      NO_ASSERT_CHECK='TRUE';
      NO_DIR_CHECK='TRUE';
      ALLOW_CONNECT='TRUE';
    'GND'<44>:
      PIN_NUMBER='(0,0,0,0,0,0,AB1)';
      PINUSE='GROUND';
      NO_LOAD_CHECK='Both';
      NO_IO_CHECK='Both';
      NO_ASSERT_CHECK='TRUE';
      NO_DIR_CHECK='TRUE';
      ALLOW_CONNECT='TRUE';
    'GND'<43>:
      PIN_NUMBER='(0,0,0,0,0,0,AA21)';
      PINUSE='GROUND';
      NO_LOAD_CHECK='Both';
      NO_IO_CHECK='Both';
      NO_ASSERT_CHECK='TRUE';
      NO_DIR_CHECK='TRUE';
      ALLOW_CONNECT='TRUE';
    'GND'<42>:
      PIN_NUMBER='(0,0,0,0,0,0,AA2)';
      PINUSE='GROUND';
      NO_LOAD_CHECK='Both';
      NO_IO_CHECK='Both';
      NO_ASSERT_CHECK='TRUE';
      NO_DIR_CHECK='TRUE';
      ALLOW_CONNECT='TRUE';
    'GND'<41>:
      PIN_NUMBER='(0,0,0,0,0,0,V18)';
      PINUSE='GROUND';
      NO_LOAD_CHECK='Both';
      NO_IO_CHECK='Both';
      NO_ASSERT_CHECK='TRUE';
      NO_DIR_CHECK='TRUE';
      ALLOW_CONNECT='TRUE';
    'GND'<40>:
      PIN_NUMBER='(0,0,0,0,0,0,V5)';
      PINUSE='GROUND';
      NO_LOAD_CHECK='Both';
      NO_IO_CHECK='Both';
      NO_ASSERT_CHECK='TRUE';
      NO_DIR_CHECK='TRUE';
      ALLOW_CONNECT='TRUE';
    'GND'<39>:
      PIN_NUMBER='(0,0,0,0,0,0,R15)';
      PINUSE='GROUND';
      NO_LOAD_CHECK='Both';
      NO_IO_CHECK='Both';
      NO_ASSERT_CHECK='TRUE';
      NO_DIR_CHECK='TRUE';
      ALLOW_CONNECT='TRUE';
    'GND'<38>:
      PIN_NUMBER='(0,0,0,0,0,0,R8)';
      PINUSE='GROUND';
      NO_LOAD_CHECK='Both';
      NO_IO_CHECK='Both';
      NO_ASSERT_CHECK='TRUE';
      NO_DIR_CHECK='TRUE';
      ALLOW_CONNECT='TRUE';
    'GND'<37>:
      PIN_NUMBER='(0,0,0,0,0,0,P22)';
      PINUSE='GROUND';
      NO_LOAD_CHECK='Both';
      NO_IO_CHECK='Both';
      NO_ASSERT_CHECK='TRUE';
      NO_DIR_CHECK='TRUE';
      ALLOW_CONNECT='TRUE';
    'GND'<36>:
      PIN_NUMBER='(0,0,0,0,0,0,P14)';
      PINUSE='GROUND';
      NO_LOAD_CHECK='Both';
      NO_IO_CHECK='Both';
      NO_ASSERT_CHECK='TRUE';
      NO_DIR_CHECK='TRUE';
      ALLOW_CONNECT='TRUE';
    'GND'<35>:
      PIN_NUMBER='(0,0,0,0,0,0,P13)';
      PINUSE='GROUND';
      NO_LOAD_CHECK='Both';
      NO_IO_CHECK='Both';
      NO_ASSERT_CHECK='TRUE';
      NO_DIR_CHECK='TRUE';
      ALLOW_CONNECT='TRUE';
    'GND'<34>:
      PIN_NUMBER='(0,0,0,0,0,0,P12)';
      PINUSE='GROUND';
      NO_LOAD_CHECK='Both';
      NO_IO_CHECK='Both';
      NO_ASSERT_CHECK='TRUE';
      NO_DIR_CHECK='TRUE';
      ALLOW_CONNECT='TRUE';
    'GND'<33>:
      PIN_NUMBER='(0,0,0,0,0,0,P11)';
      PINUSE='GROUND';
      NO_LOAD_CHECK='Both';
      NO_IO_CHECK='Both';
      NO_ASSERT_CHECK='TRUE';
      NO_DIR_CHECK='TRUE';
      ALLOW_CONNECT='TRUE';
    'GND'<32>:
      PIN_NUMBER='(0,0,0,0,0,0,P10)';
      PINUSE='GROUND';
      NO_LOAD_CHECK='Both';
      NO_IO_CHECK='Both';
      NO_ASSERT_CHECK='TRUE';
      NO_DIR_CHECK='TRUE';
      ALLOW_CONNECT='TRUE';
    'GND'<31>:
      PIN_NUMBER='(0,0,0,0,0,0,P9)';
      PINUSE='GROUND';
      NO_LOAD_CHECK='Both';
      NO_IO_CHECK='Both';
      NO_ASSERT_CHECK='TRUE';
      NO_DIR_CHECK='TRUE';
      ALLOW_CONNECT='TRUE';
    'GND'<30>:
      PIN_NUMBER='(0,0,0,0,0,0,P1)';
      PINUSE='GROUND';
      NO_LOAD_CHECK='Both';
      NO_IO_CHECK='Both';
      NO_ASSERT_CHECK='TRUE';
      NO_DIR_CHECK='TRUE';
      ALLOW_CONNECT='TRUE';
    'GND'<29>:
      PIN_NUMBER='(0,0,0,0,0,0,N14)';
      PINUSE='GROUND';
      NO_LOAD_CHECK='Both';
      NO_IO_CHECK='Both';
      NO_ASSERT_CHECK='TRUE';
      NO_DIR_CHECK='TRUE';
      ALLOW_CONNECT='TRUE';
    'GND'<28>:
      PIN_NUMBER='(0,0,0,0,0,0,N9)';
      PINUSE='GROUND';
      NO_LOAD_CHECK='Both';
      NO_IO_CHECK='Both';
      NO_ASSERT_CHECK='TRUE';
      NO_DIR_CHECK='TRUE';
      ALLOW_CONNECT='TRUE';
    'GND'<27>:
      PIN_NUMBER='(0,0,0,0,0,0,M14)';
      PINUSE='GROUND';
      NO_LOAD_CHECK='Both';
      NO_IO_CHECK='Both';
      NO_ASSERT_CHECK='TRUE';
      NO_DIR_CHECK='TRUE';
      ALLOW_CONNECT='TRUE';
    'GND'<26>:
      PIN_NUMBER='(0,0,0,0,0,0,M12)';
      PINUSE='GROUND';
      NO_LOAD_CHECK='Both';
      NO_IO_CHECK='Both';
      NO_ASSERT_CHECK='TRUE';
      NO_DIR_CHECK='TRUE';
      ALLOW_CONNECT='TRUE';
    'GND'<25>:
      PIN_NUMBER='(0,0,0,0,0,0,M11)';
      PINUSE='GROUND';
      NO_LOAD_CHECK='Both';
      NO_IO_CHECK='Both';
      NO_ASSERT_CHECK='TRUE';
      NO_DIR_CHECK='TRUE';
      ALLOW_CONNECT='TRUE';
    'GND'<24>:
      PIN_NUMBER='(0,0,0,0,0,0,M9)';
      PINUSE='GROUND';
      NO_LOAD_CHECK='Both';
      NO_IO_CHECK='Both';
      NO_ASSERT_CHECK='TRUE';
      NO_DIR_CHECK='TRUE';
      ALLOW_CONNECT='TRUE';
    'GND'<23>:
      PIN_NUMBER='(0,0,0,0,0,0,L14)';
      PINUSE='GROUND';
      NO_LOAD_CHECK='Both';
      NO_IO_CHECK='Both';
      NO_ASSERT_CHECK='TRUE';
      NO_DIR_CHECK='TRUE';
      ALLOW_CONNECT='TRUE';
    'GND'<22>:
      PIN_NUMBER='(0,0,0,0,0,0,L12)';
      PINUSE='GROUND';
      NO_LOAD_CHECK='Both';
      NO_IO_CHECK='Both';
      NO_ASSERT_CHECK='TRUE';
      NO_DIR_CHECK='TRUE';
      ALLOW_CONNECT='TRUE';
    'GND'<21>:
      PIN_NUMBER='(0,0,0,0,0,0,L11)';
      PINUSE='GROUND';
      NO_LOAD_CHECK='Both';
      NO_IO_CHECK='Both';
      NO_ASSERT_CHECK='TRUE';
      NO_DIR_CHECK='TRUE';
      ALLOW_CONNECT='TRUE';
    'GND'<20>:
      PIN_NUMBER='(0,0,0,0,0,0,L9)';
      PINUSE='GROUND';
      NO_LOAD_CHECK='Both';
      NO_IO_CHECK='Both';
      NO_ASSERT_CHECK='TRUE';
      NO_DIR_CHECK='TRUE';
      ALLOW_CONNECT='TRUE';
    'GND'<19>:
      PIN_NUMBER='(0,0,0,0,0,0,K14)';
      PINUSE='GROUND';
      NO_LOAD_CHECK='Both';
      NO_IO_CHECK='Both';
      NO_ASSERT_CHECK='TRUE';
      NO_DIR_CHECK='TRUE';
      ALLOW_CONNECT='TRUE';
    'GND'<18>:
      PIN_NUMBER='(0,0,0,0,0,0,K9)';
      PINUSE='GROUND';
      NO_LOAD_CHECK='Both';
      NO_IO_CHECK='Both';
      NO_ASSERT_CHECK='TRUE';
      NO_DIR_CHECK='TRUE';
      ALLOW_CONNECT='TRUE';
    'GND'<17>:
      PIN_NUMBER='(0,0,0,0,0,0,J22)';
      PINUSE='GROUND';
      NO_LOAD_CHECK='Both';
      NO_IO_CHECK='Both';
      NO_ASSERT_CHECK='TRUE';
      NO_DIR_CHECK='TRUE';
      ALLOW_CONNECT='TRUE';
    'GND'<16>:
      PIN_NUMBER='(0,0,0,0,0,0,J14)';
      PINUSE='GROUND';
      NO_LOAD_CHECK='Both';
      NO_IO_CHECK='Both';
      NO_ASSERT_CHECK='TRUE';
      NO_DIR_CHECK='TRUE';
      ALLOW_CONNECT='TRUE';
    'GND'<15>:
      PIN_NUMBER='(0,0,0,0,0,0,J13)';
      PINUSE='GROUND';
      NO_LOAD_CHECK='Both';
      NO_IO_CHECK='Both';
      NO_ASSERT_CHECK='TRUE';
      NO_DIR_CHECK='TRUE';
      ALLOW_CONNECT='TRUE';
    'GND'<14>:
      PIN_NUMBER='(0,0,0,0,0,0,J12)';
      PINUSE='GROUND';
      NO_LOAD_CHECK='Both';
      NO_IO_CHECK='Both';
      NO_ASSERT_CHECK='TRUE';
      NO_DIR_CHECK='TRUE';
      ALLOW_CONNECT='TRUE';
    'GND'<13>:
      PIN_NUMBER='(0,0,0,0,0,0,J11)';
      PINUSE='GROUND';
      NO_LOAD_CHECK='Both';
      NO_IO_CHECK='Both';
      NO_ASSERT_CHECK='TRUE';
      NO_DIR_CHECK='TRUE';
      ALLOW_CONNECT='TRUE';
    'GND'<12>:
      PIN_NUMBER='(0,0,0,0,0,0,J10)';
      PINUSE='GROUND';
      NO_LOAD_CHECK='Both';
      NO_IO_CHECK='Both';
      NO_ASSERT_CHECK='TRUE';
      NO_DIR_CHECK='TRUE';
      ALLOW_CONNECT='TRUE';
    'GND'<11>:
      PIN_NUMBER='(0,0,0,0,0,0,J9)';
      PINUSE='GROUND';
      NO_LOAD_CHECK='Both';
      NO_IO_CHECK='Both';
      NO_ASSERT_CHECK='TRUE';
      NO_DIR_CHECK='TRUE';
      ALLOW_CONNECT='TRUE';
    'GND'<10>:
      PIN_NUMBER='(0,0,0,0,0,0,J1)';
      PINUSE='GROUND';
      NO_LOAD_CHECK='Both';
      NO_IO_CHECK='Both';
      NO_ASSERT_CHECK='TRUE';
      NO_DIR_CHECK='TRUE';
      ALLOW_CONNECT='TRUE';
    'GND'<9>:
      PIN_NUMBER='(0,0,0,0,0,0,H15)';
      PINUSE='GROUND';
      NO_LOAD_CHECK='Both';
      NO_IO_CHECK='Both';
      NO_ASSERT_CHECK='TRUE';
      NO_DIR_CHECK='TRUE';
      ALLOW_CONNECT='TRUE';
    'GND'<8>:
      PIN_NUMBER='(0,0,0,0,0,0,H8)';
      PINUSE='GROUND';
      NO_LOAD_CHECK='Both';
      NO_IO_CHECK='Both';
      NO_ASSERT_CHECK='TRUE';
      NO_DIR_CHECK='TRUE';
      ALLOW_CONNECT='TRUE';
    'GND'<7>:
      PIN_NUMBER='(0,0,0,0,0,0,E18)';
      PINUSE='GROUND';
      NO_LOAD_CHECK='Both';
      NO_IO_CHECK='Both';
      NO_ASSERT_CHECK='TRUE';
      NO_DIR_CHECK='TRUE';
      ALLOW_CONNECT='TRUE';
    'GND'<6>:
      PIN_NUMBER='(0,0,0,0,0,0,E5)';
      PINUSE='GROUND';
      NO_LOAD_CHECK='Both';
      NO_IO_CHECK='Both';
      NO_ASSERT_CHECK='TRUE';
      NO_DIR_CHECK='TRUE';
      ALLOW_CONNECT='TRUE';
    'GND'<5>:
      PIN_NUMBER='(0,0,0,0,0,0,B21)';
      PINUSE='GROUND';
      NO_LOAD_CHECK='Both';
      NO_IO_CHECK='Both';
      NO_ASSERT_CHECK='TRUE';
      NO_DIR_CHECK='TRUE';
      ALLOW_CONNECT='TRUE';
    'GND'<4>:
      PIN_NUMBER='(0,0,0,0,0,0,B2)';
      PINUSE='GROUND';
      NO_LOAD_CHECK='Both';
      NO_IO_CHECK='Both';
      NO_ASSERT_CHECK='TRUE';
      NO_DIR_CHECK='TRUE';
      ALLOW_CONNECT='TRUE';
    'GND'<3>:
      PIN_NUMBER='(0,0,0,0,0,0,A22)';
      PINUSE='GROUND';
      NO_LOAD_CHECK='Both';
      NO_IO_CHECK='Both';
      NO_ASSERT_CHECK='TRUE';
      NO_DIR_CHECK='TRUE';
      ALLOW_CONNECT='TRUE';
    'GND'<2>:
      PIN_NUMBER='(0,0,0,0,0,0,A14)';
      PINUSE='GROUND';
      NO_LOAD_CHECK='Both';
      NO_IO_CHECK='Both';
      NO_ASSERT_CHECK='TRUE';
      NO_DIR_CHECK='TRUE';
      ALLOW_CONNECT='TRUE';
    'GND'<1>:
      PIN_NUMBER='(0,0,0,0,0,0,A9)';
      PINUSE='GROUND';
      NO_LOAD_CHECK='Both';
      NO_IO_CHECK='Both';
      NO_ASSERT_CHECK='TRUE';
      NO_DIR_CHECK='TRUE';
      ALLOW_CONNECT='TRUE';
    'GND'<0>:
      PIN_NUMBER='(0,0,0,0,0,0,A1)';
      PINUSE='GROUND';
      NO_LOAD_CHECK='Both';
      NO_IO_CHECK='Both';
      NO_ASSERT_CHECK='TRUE';
      NO_DIR_CHECK='TRUE';
      ALLOW_CONNECT='TRUE';
    'NC'<48>:
      PIN_NUMBER='(0,0,0,0,Y11,0,0)';
      PINUSE='NC';
      NO_LOAD_CHECK='Both';
      NO_IO_CHECK='Both';
      NO_ASSERT_CHECK='TRUE';
      NO_DIR_CHECK='TRUE';
      ALLOW_CONNECT='TRUE';
    'NC'<47>:
      PIN_NUMBER='(0,0,0,0,Y9,0,0)';
      PINUSE='NC';
      NO_LOAD_CHECK='Both';
      NO_IO_CHECK='Both';
      NO_ASSERT_CHECK='TRUE';
      NO_DIR_CHECK='TRUE';
      ALLOW_CONNECT='TRUE';
    'NC'<46>:
      PIN_NUMBER='(0,0,0,0,W21,0,0)';
      PINUSE='NC';
      NO_LOAD_CHECK='Both';
      NO_IO_CHECK='Both';
      NO_ASSERT_CHECK='TRUE';
      NO_DIR_CHECK='TRUE';
      ALLOW_CONNECT='TRUE';
    'NC'<45>:
      PIN_NUMBER='(0,0,0,0,V20,0,0)';
      PINUSE='NC';
      NO_LOAD_CHECK='Both';
      NO_IO_CHECK='Both';
      NO_ASSERT_CHECK='TRUE';
      NO_DIR_CHECK='TRUE';
      ALLOW_CONNECT='TRUE';
    'NC'<44>:
      PIN_NUMBER='(0,0,0,0,V10,0,0)';
      PINUSE='NC';
      NO_LOAD_CHECK='Both';
      NO_IO_CHECK='Both';
      NO_ASSERT_CHECK='TRUE';
      NO_DIR_CHECK='TRUE';
      ALLOW_CONNECT='TRUE';
    'NC'<43>:
      PIN_NUMBER='(0,0,0,0,U14,0,0)';
      PINUSE='NC';
      NO_LOAD_CHECK='Both';
      NO_IO_CHECK='Both';
      NO_ASSERT_CHECK='TRUE';
      NO_DIR_CHECK='TRUE';
      ALLOW_CONNECT='TRUE';
    'NC'<42>:
      PIN_NUMBER='(0,0,0,0,U9,0,0)';
      PINUSE='NC';
      NO_LOAD_CHECK='Both';
      NO_IO_CHECK='Both';
      NO_ASSERT_CHECK='TRUE';
      NO_DIR_CHECK='TRUE';
      ALLOW_CONNECT='TRUE';
    'NC'<41>:
      PIN_NUMBER='(0,0,0,0,U1,0,0)';
      PINUSE='NC';
      NO_LOAD_CHECK='Both';
      NO_IO_CHECK='Both';
      NO_ASSERT_CHECK='TRUE';
      NO_DIR_CHECK='TRUE';
      ALLOW_CONNECT='TRUE';
    'NC'<40>:
      PIN_NUMBER='(0,0,0,0,T14,0,0)';
      PINUSE='NC';
      NO_LOAD_CHECK='Both';
      NO_IO_CHECK='Both';
      NO_ASSERT_CHECK='TRUE';
      NO_DIR_CHECK='TRUE';
      ALLOW_CONNECT='TRUE';
    'NC'<39>:
      PIN_NUMBER='(0,0,0,0,T9,0,0)';
      PINUSE='NC';
      NO_LOAD_CHECK='Both';
      NO_IO_CHECK='Both';
      NO_ASSERT_CHECK='TRUE';
      NO_DIR_CHECK='TRUE';
      ALLOW_CONNECT='TRUE';
    'NC'<38>:
      PIN_NUMBER='(0,0,0,0,T3,0,0)';
      PINUSE='NC';
      NO_LOAD_CHECK='Both';
      NO_IO_CHECK='Both';
      NO_ASSERT_CHECK='TRUE';
      NO_DIR_CHECK='TRUE';
      ALLOW_CONNECT='TRUE';
    'NC'<37>:
      PIN_NUMBER='(0,0,0,0,T2,0,0)';
      PINUSE='NC';
      NO_LOAD_CHECK='Both';
      NO_IO_CHECK='Both';
      NO_ASSERT_CHECK='TRUE';
      NO_DIR_CHECK='TRUE';
      ALLOW_CONNECT='TRUE';
    'NC'<36>:
      PIN_NUMBER='(0,0,0,0,T1,0,0)';
      PINUSE='NC';
      NO_LOAD_CHECK='Both';
      NO_IO_CHECK='Both';
      NO_ASSERT_CHECK='TRUE';
      NO_DIR_CHECK='TRUE';
      ALLOW_CONNECT='TRUE';
    'NC'<35>:
      PIN_NUMBER='(0,0,0,0,R5,0,0)';
      PINUSE='NC';
      NO_LOAD_CHECK='Both';
      NO_IO_CHECK='Both';
      NO_ASSERT_CHECK='TRUE';
      NO_DIR_CHECK='TRUE';
      ALLOW_CONNECT='TRUE';
    'NC'<34>:
      PIN_NUMBER='(0,0,0,0,R4,0,0)';
      PINUSE='NC';
      NO_LOAD_CHECK='Both';
      NO_IO_CHECK='Both';
      NO_ASSERT_CHECK='TRUE';
      NO_DIR_CHECK='TRUE';
      ALLOW_CONNECT='TRUE';
    'NC'<33>:
      PIN_NUMBER='(0,0,0,0,P17,0,0)';
      PINUSE='NC';
      NO_LOAD_CHECK='Both';
      NO_IO_CHECK='Both';
      NO_ASSERT_CHECK='TRUE';
      NO_DIR_CHECK='TRUE';
      ALLOW_CONNECT='TRUE';
    'NC'<32>:
      PIN_NUMBER='(0,0,0,0,P16,0,0)';
      PINUSE='NC';
      NO_LOAD_CHECK='Both';
      NO_IO_CHECK='Both';
      NO_ASSERT_CHECK='TRUE';
      NO_DIR_CHECK='TRUE';
      ALLOW_CONNECT='TRUE';
    'NC'<31>:
      PIN_NUMBER='(0,0,0,0,P5,0,0)';
      PINUSE='NC';
      NO_LOAD_CHECK='Both';
      NO_IO_CHECK='Both';
      NO_ASSERT_CHECK='TRUE';
      NO_DIR_CHECK='TRUE';
      ALLOW_CONNECT='TRUE';
    'NC'<30>:
      PIN_NUMBER='(0,0,0,0,P4,0,0)';
      PINUSE='NC';
      NO_LOAD_CHECK='Both';
      NO_IO_CHECK='Both';
      NO_ASSERT_CHECK='TRUE';
      NO_DIR_CHECK='TRUE';
      ALLOW_CONNECT='TRUE';
    'NC'<29>:
      PIN_NUMBER='(0,0,0,0,L19,0,0)';
      PINUSE='NC';
      NO_LOAD_CHECK='Both';
      NO_IO_CHECK='Both';
      NO_ASSERT_CHECK='TRUE';
      NO_DIR_CHECK='TRUE';
      ALLOW_CONNECT='TRUE';
    'NC'<28>:
      PIN_NUMBER='(0,0,0,0,L18,0,0)';
      PINUSE='NC';
      NO_LOAD_CHECK='Both';
      NO_IO_CHECK='Both';
      NO_ASSERT_CHECK='TRUE';
      NO_DIR_CHECK='TRUE';
      ALLOW_CONNECT='TRUE';
    'NC'<27>:
      PIN_NUMBER='(0,0,0,0,J20,0,0)';
      PINUSE='NC';
      NO_LOAD_CHECK='Both';
      NO_IO_CHECK='Both';
      NO_ASSERT_CHECK='TRUE';
      NO_DIR_CHECK='TRUE';
      ALLOW_CONNECT='TRUE';
    'NC'<26>:
      PIN_NUMBER='(0,0,0,0,J7,0,0)';
      PINUSE='NC';
      NO_LOAD_CHECK='Both';
      NO_IO_CHECK='Both';
      NO_ASSERT_CHECK='TRUE';
      NO_DIR_CHECK='TRUE';
      ALLOW_CONNECT='TRUE';
    'NC'<25>:
      PIN_NUMBER='(0,0,0,0,J6,0,0)';
      PINUSE='NC';
      NO_LOAD_CHECK='Both';
      NO_IO_CHECK='Both';
      NO_ASSERT_CHECK='TRUE';
      NO_DIR_CHECK='TRUE';
      ALLOW_CONNECT='TRUE';
    'NC'<24>:
      PIN_NUMBER='(0,0,0,0,H22,0,0)';
      PINUSE='NC';
      NO_LOAD_CHECK='Both';
      NO_IO_CHECK='Both';
      NO_ASSERT_CHECK='TRUE';
      NO_DIR_CHECK='TRUE';
      ALLOW_CONNECT='TRUE';
    'NC'<23>:
      PIN_NUMBER='(0,0,0,0,H19,0,0)';
      PINUSE='NC';
      NO_LOAD_CHECK='Both';
      NO_IO_CHECK='Both';
      NO_ASSERT_CHECK='TRUE';
      NO_DIR_CHECK='TRUE';
      ALLOW_CONNECT='TRUE';
    'NC'<22>:
      PIN_NUMBER='(0,0,0,0,H18,0,0)';
      PINUSE='NC';
      NO_LOAD_CHECK='Both';
      NO_IO_CHECK='Both';
      NO_ASSERT_CHECK='TRUE';
      NO_DIR_CHECK='TRUE';
      ALLOW_CONNECT='TRUE';
    'NC'<21>:
      PIN_NUMBER='(0,0,0,0,G20,0,0)';
      PINUSE='NC';
      NO_LOAD_CHECK='Both';
      NO_IO_CHECK='Both';
      NO_ASSERT_CHECK='TRUE';
      NO_DIR_CHECK='TRUE';
      ALLOW_CONNECT='TRUE';
    'NC'<20>:
      PIN_NUMBER='(0,0,0,0,G14,0,0)';
      PINUSE='NC';
      NO_LOAD_CHECK='Both';
      NO_IO_CHECK='Both';
      NO_ASSERT_CHECK='TRUE';
      NO_DIR_CHECK='TRUE';
      ALLOW_CONNECT='TRUE';
    'NC'<19>:
      PIN_NUMBER='(0,0,0,0,G9,0,0)';
      PINUSE='NC';
      NO_LOAD_CHECK='Both';
      NO_IO_CHECK='Both';
      NO_ASSERT_CHECK='TRUE';
      NO_DIR_CHECK='TRUE';
      ALLOW_CONNECT='TRUE';
    'NC'<18>:
      PIN_NUMBER='(0,0,0,0,F22,0,0)';
      PINUSE='NC';
      NO_LOAD_CHECK='Both';
      NO_IO_CHECK='Both';
      NO_ASSERT_CHECK='TRUE';
      NO_DIR_CHECK='TRUE';
      ALLOW_CONNECT='TRUE';
    'NC'<17>:
      PIN_NUMBER='(0,0,0,0,F14,0,0)';
      PINUSE='NC';
      NO_LOAD_CHECK='Both';
      NO_IO_CHECK='Both';
      NO_ASSERT_CHECK='TRUE';
      NO_DIR_CHECK='TRUE';
      ALLOW_CONNECT='TRUE';
    'NC'<16>:
      PIN_NUMBER='(0,0,0,0,F9,0,0)';
      PINUSE='NC';
      NO_LOAD_CHECK='Both';
      NO_IO_CHECK='Both';
      NO_ASSERT_CHECK='TRUE';
      NO_DIR_CHECK='TRUE';
      ALLOW_CONNECT='TRUE';
    'NC'<15>:
      PIN_NUMBER='(0,0,0,0,F7,0,0)';
      PINUSE='NC';
      NO_LOAD_CHECK='Both';
      NO_IO_CHECK='Both';
      NO_ASSERT_CHECK='TRUE';
      NO_DIR_CHECK='TRUE';
      ALLOW_CONNECT='TRUE';
    'NC'<14>:
      PIN_NUMBER='(0,0,0,0,E13,0,0)';
      PINUSE='NC';
      NO_LOAD_CHECK='Both';
      NO_IO_CHECK='Both';
      NO_ASSERT_CHECK='TRUE';
      NO_DIR_CHECK='TRUE';
      ALLOW_CONNECT='TRUE';
    'NC'<13>:
      PIN_NUMBER='(0,0,0,0,E3,0,0)';
      PINUSE='NC';
      NO_LOAD_CHECK='Both';
      NO_IO_CHECK='Both';
      NO_ASSERT_CHECK='TRUE';
      NO_DIR_CHECK='TRUE';
      ALLOW_CONNECT='TRUE';
    'NC'<12>:
      PIN_NUMBER='(0,0,0,0,D2,0,0)';
      PINUSE='NC';
      NO_LOAD_CHECK='Both';
      NO_IO_CHECK='Both';
      NO_ASSERT_CHECK='TRUE';
      NO_DIR_CHECK='TRUE';
      ALLOW_CONNECT='TRUE';
    'NC'<11>:
      PIN_NUMBER='(0,0,0,0,C14,0,0)';
      PINUSE='NC';
      NO_LOAD_CHECK='Both';
      NO_IO_CHECK='Both';
      NO_ASSERT_CHECK='TRUE';
      NO_DIR_CHECK='TRUE';
      ALLOW_CONNECT='TRUE';
    'NC'<10>:
      PIN_NUMBER='(0,0,0,0,C12,0,0)';
      PINUSE='NC';
      NO_LOAD_CHECK='Both';
      NO_IO_CHECK='Both';
      NO_ASSERT_CHECK='TRUE';
      NO_DIR_CHECK='TRUE';
      ALLOW_CONNECT='TRUE';
    'NC'<9>:
      PIN_NUMBER='(0,0,0,0,B18,0,0)';
      PINUSE='NC';
      NO_LOAD_CHECK='Both';
      NO_IO_CHECK='Both';
      NO_ASSERT_CHECK='TRUE';
      NO_DIR_CHECK='TRUE';
      ALLOW_CONNECT='TRUE';
    'NC'<8>:
      PIN_NUMBER='(0,0,0,0,B5,0,0)';
      PINUSE='NC';
      NO_LOAD_CHECK='Both';
      NO_IO_CHECK='Both';
      NO_ASSERT_CHECK='TRUE';
      NO_DIR_CHECK='TRUE';
      ALLOW_CONNECT='TRUE';
    'NC'<7>:
      PIN_NUMBER='(0,0,0,0,AB19,0,0)';
      PINUSE='NC';
      NO_LOAD_CHECK='Both';
      NO_IO_CHECK='Both';
      NO_ASSERT_CHECK='TRUE';
      NO_DIR_CHECK='TRUE';
      ALLOW_CONNECT='TRUE';
    'NC'<6>:
      PIN_NUMBER='(0,0,0,0,AB8,0,0)';
      PINUSE='NC';
      NO_LOAD_CHECK='Both';
      NO_IO_CHECK='Both';
      NO_ASSERT_CHECK='TRUE';
      NO_DIR_CHECK='TRUE';
      ALLOW_CONNECT='TRUE';
    'NC'<5>:
      PIN_NUMBER='(0,0,0,0,AB4,0,0)';
      PINUSE='NC';
      NO_LOAD_CHECK='Both';
      NO_IO_CHECK='Both';
      NO_ASSERT_CHECK='TRUE';
      NO_DIR_CHECK='TRUE';
      ALLOW_CONNECT='TRUE';
    'NC'<4>:
      PIN_NUMBER='(0,0,0,0,AA18,0,0)';
      PINUSE='NC';
      NO_LOAD_CHECK='Both';
      NO_IO_CHECK='Both';
      NO_ASSERT_CHECK='TRUE';
      NO_DIR_CHECK='TRUE';
      ALLOW_CONNECT='TRUE';
    'NC'<3>:
      PIN_NUMBER='(0,0,0,0,AA5,0,0)';
      PINUSE='NC';
      NO_LOAD_CHECK='Both';
      NO_IO_CHECK='Both';
      NO_ASSERT_CHECK='TRUE';
      NO_DIR_CHECK='TRUE';
      ALLOW_CONNECT='TRUE';
    'NC'<2>:
      PIN_NUMBER='(0,0,0,0,A19,0,0)';
      PINUSE='NC';
      NO_LOAD_CHECK='Both';
      NO_IO_CHECK='Both';
      NO_ASSERT_CHECK='TRUE';
      NO_DIR_CHECK='TRUE';
      ALLOW_CONNECT='TRUE';
    'NC'<1>:
      PIN_NUMBER='(0,0,0,0,A15,0,0)';
      PINUSE='NC';
      NO_LOAD_CHECK='Both';
      NO_IO_CHECK='Both';
      NO_ASSERT_CHECK='TRUE';
      NO_DIR_CHECK='TRUE';
      ALLOW_CONNECT='TRUE';
    'NC'<0>:
      PIN_NUMBER='(0,0,0,0,A4,0,0)';
      PINUSE='NC';
      NO_LOAD_CHECK='Both';
      NO_IO_CHECK='Both';
      NO_ASSERT_CHECK='TRUE';
      NO_DIR_CHECK='TRUE';
      ALLOW_CONNECT='TRUE';
    'PB10A':
      PIN_NUMBER='(V8,0,0,0,0,0,0)';
      BIDIRECTIONAL='TRUE';
      INPUT_LOAD='(-0.01,0.01)';
      OUTPUT_LOAD='(1.0,-1.0)';
    'PB10B':
      PIN_NUMBER='(W8,0,0,0,0,0,0)';
      BIDIRECTIONAL='TRUE';
      INPUT_LOAD='(-0.01,0.01)';
      OUTPUT_LOAD='(1.0,-1.0)';
    'PB10C':
      PIN_NUMBER='(AB5,0,0,0,0,0,0)';
      BIDIRECTIONAL='TRUE';
      INPUT_LOAD='(-0.01,0.01)';
      OUTPUT_LOAD='(1.0,-1.0)';
    'PB10D':
      PIN_NUMBER='(Y6,0,0,0,0,0,0)';
      BIDIRECTIONAL='TRUE';
      INPUT_LOAD='(-0.01,0.01)';
      OUTPUT_LOAD='(1.0,-1.0)';
    'PB12A_MCLK_CCLK':
      PIN_NUMBER='(AB6,0,0,0,0,0,0)';
      BIDIRECTIONAL='TRUE';
      INPUT_LOAD='(-0.01,0.01)';
      OUTPUT_LOAD='(1.0,-1.0)';
    'PB12B_SO_SPISO':
      PIN_NUMBER='(Y7,0,0,0,0,0,0)';
      BIDIRECTIONAL='TRUE';
      INPUT_LOAD='(-0.01,0.01)';
      OUTPUT_LOAD='(1.0,-1.0)';
    'PB12C':
      PIN_NUMBER='(V9,0,0,0,0,0,0)';
      BIDIRECTIONAL='TRUE';
      INPUT_LOAD='(-0.01,0.01)';
      OUTPUT_LOAD='(1.0,-1.0)';
    'PB12D':
      PIN_NUMBER='(W9,0,0,0,0,0,0)';
      BIDIRECTIONAL='TRUE';
      INPUT_LOAD='(-0.01,0.01)';
      OUTPUT_LOAD='(1.0,-1.0)';
    'PB13A':
      PIN_NUMBER='(AA7,0,0,0,0,0,0)';
      BIDIRECTIONAL='TRUE';
      INPUT_LOAD='(-0.01,0.01)';
      OUTPUT_LOAD='(1.0,-1.0)';
    'PB13B':
      PIN_NUMBER='(AB7,0,0,0,0,0,0)';
      BIDIRECTIONAL='TRUE';
      INPUT_LOAD='(-0.01,0.01)';
      OUTPUT_LOAD='(1.0,-1.0)';
    'PB13C':
      PIN_NUMBER='(U10,0,0,0,0,0,0)';
      BIDIRECTIONAL='TRUE';
      INPUT_LOAD='(-0.01,0.01)';
      OUTPUT_LOAD='(1.0,-1.0)';
    'PB13D':
      PIN_NUMBER='(T10,0,0,0,0,0,0)';
      BIDIRECTIONAL='TRUE';
      INPUT_LOAD='(-0.01,0.01)';
      OUTPUT_LOAD='(1.0,-1.0)';
    'PB15A':
      PIN_NUMBER='(V11,0,0,0,0,0,0)';
      BIDIRECTIONAL='TRUE';
      INPUT_LOAD='(-0.01,0.01)';
      OUTPUT_LOAD='(1.0,-1.0)';
    'PB15B':
      PIN_NUMBER='(W11,0,0,0,0,0,0)';
      BIDIRECTIONAL='TRUE';
      INPUT_LOAD='(-0.01,0.01)';
      OUTPUT_LOAD='(1.0,-1.0)';
    'PB15C':
      PIN_NUMBER='(Y8,0,0,0,0,0,0)';
      BIDIRECTIONAL='TRUE';
      INPUT_LOAD='(-0.01,0.01)';
      OUTPUT_LOAD='(1.0,-1.0)';
    'PB15D':
      PIN_NUMBER='(AA8,0,0,0,0,0,0)';
      BIDIRECTIONAL='TRUE';
      INPUT_LOAD='(-0.01,0.01)';
      OUTPUT_LOAD='(1.0,-1.0)';
    'PB16A_PCLKT2_0':
      PIN_NUMBER='(AA9,0,0,0,0,0,0)';
      BIDIRECTIONAL='TRUE';
      INPUT_LOAD='(-0.01,0.01)';
      OUTPUT_LOAD='(1.0,-1.0)';
    'PB16B_PCLKC2_0':
      PIN_NUMBER='(Y10,0,0,0,0,0,0)';
      BIDIRECTIONAL='TRUE';
      INPUT_LOAD='(-0.01,0.01)';
      OUTPUT_LOAD='(1.0,-1.0)';
    'PB16C':
      PIN_NUMBER='(U11,0,0,0,0,0,0)';
      BIDIRECTIONAL='TRUE';
      INPUT_LOAD='(-0.01,0.01)';
      OUTPUT_LOAD='(1.0,-1.0)';
    'PB16D':
      PIN_NUMBER='(T11,0,0,0,0,0,0)';
      BIDIRECTIONAL='TRUE';
      INPUT_LOAD='(-0.01,0.01)';
      OUTPUT_LOAD='(1.0,-1.0)';
    'PB18A':
      PIN_NUMBER='(AA10,0,0,0,0,0,0)';
      BIDIRECTIONAL='TRUE';
      INPUT_LOAD='(-0.01,0.01)';
      OUTPUT_LOAD='(1.0,-1.0)';
    'PB18B':
      PIN_NUMBER='(AB10,0,0,0,0,0,0)';
      BIDIRECTIONAL='TRUE';
      INPUT_LOAD='(-0.01,0.01)';
      OUTPUT_LOAD='(1.0,-1.0)';
    'PB18C':
      PIN_NUMBER='(AA11,0,0,0,0,0,0)';
      BIDIRECTIONAL='TRUE';
      INPUT_LOAD='(-0.01,0.01)';
      OUTPUT_LOAD='(1.0,-1.0)';
    'PB18D':
      PIN_NUMBER='(AB11,0,0,0,0,0,0)';
      BIDIRECTIONAL='TRUE';
      INPUT_LOAD='(-0.01,0.01)';
      OUTPUT_LOAD='(1.0,-1.0)';
    'PB21A':
      PIN_NUMBER='(AB12,0,0,0,0,0,0)';
      BIDIRECTIONAL='TRUE';
      INPUT_LOAD='(-0.01,0.01)';
      OUTPUT_LOAD='(1.0,-1.0)';
    'PB21B':
      PIN_NUMBER='(AA12,0,0,0,0,0,0)';
      BIDIRECTIONAL='TRUE';
      INPUT_LOAD='(-0.01,0.01)';
      OUTPUT_LOAD='(1.0,-1.0)';
    'PB21C':
      PIN_NUMBER='(AB13,0,0,0,0,0,0)';
      BIDIRECTIONAL='TRUE';
      INPUT_LOAD='(-0.01,0.01)';
      OUTPUT_LOAD='(1.0,-1.0)';
    'PB21D':
      PIN_NUMBER='(AA13,0,0,0,0,0,0)';
      BIDIRECTIONAL='TRUE';
      INPUT_LOAD='(-0.01,0.01)';
      OUTPUT_LOAD='(1.0,-1.0)';
    'PB23A_PCLKT2_1':
      PIN_NUMBER='(Y13,0,0,0,0,0,0)';
      BIDIRECTIONAL='TRUE';
      INPUT_LOAD='(-0.01,0.01)';
      OUTPUT_LOAD='(1.0,-1.0)';
    'PB23B_PCLKC2_1':
      PIN_NUMBER='(AA14,0,0,0,0,0,0)';
      BIDIRECTIONAL='TRUE';
      INPUT_LOAD='(-0.01,0.01)';
      OUTPUT_LOAD='(1.0,-1.0)';
    'PB23C':
      PIN_NUMBER='(T12,0,0,0,0,0,0)';
      BIDIRECTIONAL='TRUE';
      INPUT_LOAD='(-0.01,0.01)';
      OUTPUT_LOAD='(1.0,-1.0)';
    'PB23D':
      PIN_NUMBER='(U12,0,0,0,0,0,0)';
      BIDIRECTIONAL='TRUE';
      INPUT_LOAD='(-0.01,0.01)';
      OUTPUT_LOAD='(1.0,-1.0)';
    'PB26A':
      PIN_NUMBER='(Y14,0,0,0,0,0,0)';
      BIDIRECTIONAL='TRUE';
      INPUT_LOAD='(-0.01,0.01)';
      OUTPUT_LOAD='(1.0,-1.0)';
    'PB26B':
      PIN_NUMBER='(AB15,0,0,0,0,0,0)';
      BIDIRECTIONAL='TRUE';
      INPUT_LOAD='(-0.01,0.01)';
      OUTPUT_LOAD='(1.0,-1.0)';
    'PB26C':
      PIN_NUMBER='(W12,0,0,0,0,0,0)';
      BIDIRECTIONAL='TRUE';
      INPUT_LOAD='(-0.01,0.01)';
      OUTPUT_LOAD='(1.0,-1.0)';
    'PB26D':
      PIN_NUMBER='(V12,0,0,0,0,0,0)';
      BIDIRECTIONAL='TRUE';
      INPUT_LOAD='(-0.01,0.01)';
      OUTPUT_LOAD='(1.0,-1.0)';
    'PB28A':
      PIN_NUMBER='(Y12,0,0,0,0,0,0)';
      BIDIRECTIONAL='TRUE';
      INPUT_LOAD='(-0.01,0.01)';
      OUTPUT_LOAD='(1.0,-1.0)';
    'PB28B':
      PIN_NUMBER='(V13,0,0,0,0,0,0)';
      BIDIRECTIONAL='TRUE';
      INPUT_LOAD='(-0.01,0.01)';
      OUTPUT_LOAD='(1.0,-1.0)';
    'PB28C':
      PIN_NUMBER='(AA15,0,0,0,0,0,0)';
      BIDIRECTIONAL='TRUE';
      INPUT_LOAD='(-0.01,0.01)';
      OUTPUT_LOAD='(1.0,-1.0)';
    'PB28D':
      PIN_NUMBER='(Y15,0,0,0,0,0,0)';
      BIDIRECTIONAL='TRUE';
      INPUT_LOAD='(-0.01,0.01)';
      OUTPUT_LOAD='(1.0,-1.0)';
    'PB29A':
      PIN_NUMBER='(AB16,0,0,0,0,0,0)';
      BIDIRECTIONAL='TRUE';
      INPUT_LOAD='(-0.01,0.01)';
      OUTPUT_LOAD='(1.0,-1.0)';
    'PB29B':
      PIN_NUMBER='(AA16,0,0,0,0,0,0)';
      BIDIRECTIONAL='TRUE';
      INPUT_LOAD='(-0.01,0.01)';
      OUTPUT_LOAD='(1.0,-1.0)';
    'PB29C':
      PIN_NUMBER='(T13,0,0,0,0,0,0)';
      BIDIRECTIONAL='TRUE';
      INPUT_LOAD='(-0.01,0.01)';
      OUTPUT_LOAD='(1.0,-1.0)';
    'PB29D':
      PIN_NUMBER='(U13,0,0,0,0,0,0)';
      BIDIRECTIONAL='TRUE';
      INPUT_LOAD='(-0.01,0.01)';
      OUTPUT_LOAD='(1.0,-1.0)';
    'PB31A':
      PIN_NUMBER='(Y16,0,0,0,0,0,0)';
      BIDIRECTIONAL='TRUE';
      INPUT_LOAD='(-0.01,0.01)';
      OUTPUT_LOAD='(1.0,-1.0)';
    'PB31B':
      PIN_NUMBER='(AB17,0,0,0,0,0,0)';
      BIDIRECTIONAL='TRUE';
      INPUT_LOAD='(-0.01,0.01)';
      OUTPUT_LOAD='(1.0,-1.0)';
    'PB31C':
      PIN_NUMBER='(W14,0,0,0,0,0,0)';
      BIDIRECTIONAL='TRUE';
      INPUT_LOAD='(-0.01,0.01)';
      OUTPUT_LOAD='(1.0,-1.0)';
    'PB31D':
      PIN_NUMBER='(V14,0,0,0,0,0,0)';
      BIDIRECTIONAL='TRUE';
      INPUT_LOAD='(-0.01,0.01)';
      OUTPUT_LOAD='(1.0,-1.0)';
    'PB32A':
      PIN_NUMBER='(Y17,0,0,0,0,0,0)';
      BIDIRECTIONAL='TRUE';
      INPUT_LOAD='(-0.01,0.01)';
      OUTPUT_LOAD='(1.0,-1.0)';
    'PB32B':
      PIN_NUMBER='(AB18,0,0,0,0,0,0)';
      BIDIRECTIONAL='TRUE';
      INPUT_LOAD='(-0.01,0.01)';
      OUTPUT_LOAD='(1.0,-1.0)';
    'PB32C':
      PIN_NUMBER='(W15,0,0,0,0,0,0)';
      BIDIRECTIONAL='TRUE';
      INPUT_LOAD='(-0.01,0.01)';
      OUTPUT_LOAD='(1.0,-1.0)';
    'PB32D':
      PIN_NUMBER='(V15,0,0,0,0,0,0)';
      BIDIRECTIONAL='TRUE';
      INPUT_LOAD='(-0.01,0.01)';
      OUTPUT_LOAD='(1.0,-1.0)';
    'PB34A':
      PIN_NUMBER='(W16,0,0,0,0,0,0)';
      BIDIRECTIONAL='TRUE';
      INPUT_LOAD='(-0.01,0.01)';
      OUTPUT_LOAD='(1.0,-1.0)';
    'PB34B':
      PIN_NUMBER='(W17,0,0,0,0,0,0)';
      BIDIRECTIONAL='TRUE';
      INPUT_LOAD='(-0.01,0.01)';
      OUTPUT_LOAD='(1.0,-1.0)';
    'PB34C':
      PIN_NUMBER='(Y18,0,0,0,0,0,0)';
      BIDIRECTIONAL='TRUE';
      INPUT_LOAD='(-0.01,0.01)';
      OUTPUT_LOAD='(1.0,-1.0)';
    'PB34D':
      PIN_NUMBER='(AA19,0,0,0,0,0,0)';
      BIDIRECTIONAL='TRUE';
      INPUT_LOAD='(-0.01,0.01)';
      OUTPUT_LOAD='(1.0,-1.0)';
    'PB35A':
      PIN_NUMBER='(AB20,0,0,0,0,0,0)';
      BIDIRECTIONAL='TRUE';
      INPUT_LOAD='(-0.01,0.01)';
      OUTPUT_LOAD='(1.0,-1.0)';
    'PB35B':
      PIN_NUMBER='(AB21,0,0,0,0,0,0)';
      BIDIRECTIONAL='TRUE';
      INPUT_LOAD='(-0.01,0.01)';
      OUTPUT_LOAD='(1.0,-1.0)';
    'PB35C':
      PIN_NUMBER='(V16,0,0,0,0,0,0)';
      BIDIRECTIONAL='TRUE';
      INPUT_LOAD='(-0.01,0.01)';
      OUTPUT_LOAD='(1.0,-1.0)';
    'PB35D':
      PIN_NUMBER='(U15,0,0,0,0,0,0)';
      BIDIRECTIONAL='TRUE';
      INPUT_LOAD='(-0.01,0.01)';
      OUTPUT_LOAD='(1.0,-1.0)';
    'PB37A':
      PIN_NUMBER='(Y19,0,0,0,0,0,0)';
      BIDIRECTIONAL='TRUE';
      INPUT_LOAD='(-0.01,0.01)';
      OUTPUT_LOAD='(1.0,-1.0)';
    'PB37B':
      PIN_NUMBER='(W18,0,0,0,0,0,0)';
      BIDIRECTIONAL='TRUE';
      INPUT_LOAD='(-0.01,0.01)';
      OUTPUT_LOAD='(1.0,-1.0)';
    'PB37C':
      PIN_NUMBER='(T15,0,0,0,0,0,0)';
      BIDIRECTIONAL='TRUE';
      INPUT_LOAD='(-0.01,0.01)';
      OUTPUT_LOAD='(1.0,-1.0)';
    'PB37D':
      PIN_NUMBER='(U16,0,0,0,0,0,0)';
      BIDIRECTIONAL='TRUE';
      INPUT_LOAD='(-0.01,0.01)';
      OUTPUT_LOAD='(1.0,-1.0)';
    'PB38A_SN':
      PIN_NUMBER='(AA20,0,0,0,0,0,0)';
      BIDIRECTIONAL='TRUE';
      INPUT_LOAD='(-0.01,0.01)';
      OUTPUT_LOAD='(1.0,-1.0)';
    'PB38B_SI_SISPI':
      PIN_NUMBER='(W19,0,0,0,0,0,0)';
      BIDIRECTIONAL='TRUE';
      INPUT_LOAD='(-0.01,0.01)';
      OUTPUT_LOAD='(1.0,-1.0)';
    'PB38C':
      PIN_NUMBER='(V17,0,0,0,0,0,0)';
      BIDIRECTIONAL='TRUE';
      INPUT_LOAD='(-0.01,0.01)';
      OUTPUT_LOAD='(1.0,-1.0)';
    'PB38D':
      PIN_NUMBER='(T16,0,0,0,0,0,0)';
      BIDIRECTIONAL='TRUE';
      INPUT_LOAD='(-0.01,0.01)';
      OUTPUT_LOAD='(1.0,-1.0)';
    'PB4A':
      PIN_NUMBER='(Y3,0,0,0,0,0,0)';
      BIDIRECTIONAL='TRUE';
      INPUT_LOAD='(-0.01,0.01)';
      OUTPUT_LOAD='(1.0,-1.0)';
    'PB4B':
      PIN_NUMBER='(AA3,0,0,0,0,0,0)';
      BIDIRECTIONAL='TRUE';
      INPUT_LOAD='(-0.01,0.01)';
      OUTPUT_LOAD='(1.0,-1.0)';
    'PB4C':
      PIN_NUMBER='(U6,0,0,0,0,0,0)';
      BIDIRECTIONAL='TRUE';
      INPUT_LOAD='(-0.01,0.01)';
      OUTPUT_LOAD='(1.0,-1.0)';
    'PB4D':
      PIN_NUMBER='(V6,0,0,0,0,0,0)';
      BIDIRECTIONAL='TRUE';
      INPUT_LOAD='(-0.01,0.01)';
      OUTPUT_LOAD='(1.0,-1.0)';
    'PB6A_CSSPIN':
      PIN_NUMBER='(W5,0,0,0,0,0,0)';
      BIDIRECTIONAL='TRUE';
      INPUT_LOAD='(-0.01,0.01)';
      OUTPUT_LOAD='(1.0,-1.0)';
    'PB6B':
      PIN_NUMBER='(Y4,0,0,0,0,0,0)';
      BIDIRECTIONAL='TRUE';
      INPUT_LOAD='(-0.01,0.01)';
      OUTPUT_LOAD='(1.0,-1.0)';
    'PB6C':
      PIN_NUMBER='(U7,0,0,0,0,0,0)';
      BIDIRECTIONAL='TRUE';
      INPUT_LOAD='(-0.01,0.01)';
      OUTPUT_LOAD='(1.0,-1.0)';
    'PB6D':
      PIN_NUMBER='(T8,0,0,0,0,0,0)';
      BIDIRECTIONAL='TRUE';
      INPUT_LOAD='(-0.01,0.01)';
      OUTPUT_LOAD='(1.0,-1.0)';
    'PB7A':
      PIN_NUMBER='(U8,0,0,0,0,0,0)';
      BIDIRECTIONAL='TRUE';
      INPUT_LOAD='(-0.01,0.01)';
      OUTPUT_LOAD='(1.0,-1.0)';
    'PB7B':
      PIN_NUMBER='(V7,0,0,0,0,0,0)';
      BIDIRECTIONAL='TRUE';
      INPUT_LOAD='(-0.01,0.01)';
      OUTPUT_LOAD='(1.0,-1.0)';
    'PB7C':
      PIN_NUMBER='(AB2,0,0,0,0,0,0)';
      BIDIRECTIONAL='TRUE';
      INPUT_LOAD='(-0.01,0.01)';
      OUTPUT_LOAD='(1.0,-1.0)';
    'PB7D':
      PIN_NUMBER='(AB3,0,0,0,0,0,0)';
      BIDIRECTIONAL='TRUE';
      INPUT_LOAD='(-0.01,0.01)';
      OUTPUT_LOAD='(1.0,-1.0)';
    'PB9A':
      PIN_NUMBER='(AA4,0,0,0,0,0,0)';
      BIDIRECTIONAL='TRUE';
      INPUT_LOAD='(-0.01,0.01)';
      OUTPUT_LOAD='(1.0,-1.0)';
    'PB9B':
      PIN_NUMBER='(Y5,0,0,0,0,0,0)';
      BIDIRECTIONAL='TRUE';
      INPUT_LOAD='(-0.01,0.01)';
      OUTPUT_LOAD='(1.0,-1.0)';
    'PB9C':
      PIN_NUMBER='(W6,0,0,0,0,0,0)';
      BIDIRECTIONAL='TRUE';
      INPUT_LOAD='(-0.01,0.01)';
      OUTPUT_LOAD='(1.0,-1.0)';
    'PB9D':
      PIN_NUMBER='(W7,0,0,0,0,0,0)';
      BIDIRECTIONAL='TRUE';
      INPUT_LOAD='(-0.01,0.01)';
      OUTPUT_LOAD='(1.0,-1.0)';
    'PL10A':
      PIN_NUMBER='(0,H1,0,0,0,0,0)';
      BIDIRECTIONAL='TRUE';
      INPUT_LOAD='(-0.01,0.01)';
      OUTPUT_LOAD='(1.0,-1.0)';
    'PL10B':
      PIN_NUMBER='(0,J3,0,0,0,0,0)';
      BIDIRECTIONAL='TRUE';
      INPUT_LOAD='(-0.01,0.01)';
      OUTPUT_LOAD='(1.0,-1.0)';
    'PL10C':
      PIN_NUMBER='(0,L5,0,0,0,0,0)';
      BIDIRECTIONAL='TRUE';
      INPUT_LOAD='(-0.01,0.01)';
      OUTPUT_LOAD='(1.0,-1.0)';
    'PL10D':
      PIN_NUMBER='(0,L4,0,0,0,0,0)';
      BIDIRECTIONAL='TRUE';
      INPUT_LOAD='(-0.01,0.01)';
      OUTPUT_LOAD='(1.0,-1.0)';
    'PL11A':
      PIN_NUMBER='(0,J2,0,0,0,0,0)';
      BIDIRECTIONAL='TRUE';
      INPUT_LOAD='(-0.01,0.01)';
      OUTPUT_LOAD='(1.0,-1.0)';
    'PL11B':
      PIN_NUMBER='(0,K3,0,0,0,0,0)';
      BIDIRECTIONAL='TRUE';
      INPUT_LOAD='(-0.01,0.01)';
      OUTPUT_LOAD='(1.0,-1.0)';
    'PL11C':
      PIN_NUMBER='(0,L6,0,0,0,0,0)';
      BIDIRECTIONAL='TRUE';
      INPUT_LOAD='(-0.01,0.01)';
      OUTPUT_LOAD='(1.0,-1.0)';
    'PL11D':
      PIN_NUMBER='(0,L7,0,0,0,0,0)';
      BIDIRECTIONAL='TRUE';
      INPUT_LOAD='(-0.01,0.01)';
      OUTPUT_LOAD='(1.0,-1.0)';
    'PL12A_PCLKT4_0':
      PIN_NUMBER='(0,K2,0,0,0,0,0)';
      BIDIRECTIONAL='TRUE';
      INPUT_LOAD='(-0.01,0.01)';
      OUTPUT_LOAD='(1.0,-1.0)';
    'PL12B_PCLKC4_0':
      PIN_NUMBER='(0,K1,0,0,0,0,0)';
      BIDIRECTIONAL='TRUE';
      INPUT_LOAD='(-0.01,0.01)';
      OUTPUT_LOAD='(1.0,-1.0)';
    'PL12C':
      PIN_NUMBER='(0,L2,0,0,0,0,0)';
      BIDIRECTIONAL='TRUE';
      INPUT_LOAD='(-0.01,0.01)';
      OUTPUT_LOAD='(1.0,-1.0)';
    'PL12D':
      PIN_NUMBER='(0,L1,0,0,0,0,0)';
      BIDIRECTIONAL='TRUE';
      INPUT_LOAD='(-0.01,0.01)';
      OUTPUT_LOAD='(1.0,-1.0)';
    'PL15A':
      PIN_NUMBER='(0,N1,0,0,0,0,0)';
      BIDIRECTIONAL='TRUE';
      INPUT_LOAD='(-0.01,0.01)';
      OUTPUT_LOAD='(1.0,-1.0)';
    'PL15B':
      PIN_NUMBER='(0,N2,0,0,0,0,0)';
      BIDIRECTIONAL='TRUE';
      INPUT_LOAD='(-0.01,0.01)';
      OUTPUT_LOAD='(1.0,-1.0)';
    'PL15C':
      PIN_NUMBER='(0,M1,0,0,0,0,0)';
      BIDIRECTIONAL='TRUE';
      INPUT_LOAD='(-0.01,0.01)';
      OUTPUT_LOAD='(1.0,-1.0)';
    'PL15D':
      PIN_NUMBER='(0,M2,0,0,0,0,0)';
      BIDIRECTIONAL='TRUE';
      INPUT_LOAD='(-0.01,0.01)';
      OUTPUT_LOAD='(1.0,-1.0)';
    'PL16A':
      PIN_NUMBER='(0,N3,0,0,0,0,0)';
      BIDIRECTIONAL='TRUE';
      INPUT_LOAD='(-0.01,0.01)';
      OUTPUT_LOAD='(1.0,-1.0)';
    'PL16B':
      PIN_NUMBER='(0,P2,0,0,0,0,0)';
      BIDIRECTIONAL='TRUE';
      INPUT_LOAD='(-0.01,0.01)';
      OUTPUT_LOAD='(1.0,-1.0)';
    'PL16C':
      PIN_NUMBER='(0,M7,0,0,0,0,0)';
      BIDIRECTIONAL='TRUE';
      INPUT_LOAD='(-0.01,0.01)';
      OUTPUT_LOAD='(1.0,-1.0)';
    'PL16D':
      PIN_NUMBER='(0,M6,0,0,0,0,0)';
      BIDIRECTIONAL='TRUE';
      INPUT_LOAD='(-0.01,0.01)';
      OUTPUT_LOAD='(1.0,-1.0)';
    'PL17A':
      PIN_NUMBER='(0,P3,0,0,0,0,0)';
      BIDIRECTIONAL='TRUE';
      INPUT_LOAD='(-0.01,0.01)';
      OUTPUT_LOAD='(1.0,-1.0)';
    'PL17B':
      PIN_NUMBER='(0,R1,0,0,0,0,0)';
      BIDIRECTIONAL='TRUE';
      INPUT_LOAD='(-0.01,0.01)';
      OUTPUT_LOAD='(1.0,-1.0)';
    'PL17C':
      PIN_NUMBER='(0,M4,0,0,0,0,0)';
      BIDIRECTIONAL='TRUE';
      INPUT_LOAD='(-0.01,0.01)';
      OUTPUT_LOAD='(1.0,-1.0)';
    'PL17D':
      PIN_NUMBER='(0,M5,0,0,0,0,0)';
      BIDIRECTIONAL='TRUE';
      INPUT_LOAD='(-0.01,0.01)';
      OUTPUT_LOAD='(1.0,-1.0)';
    'PL18A':
      PIN_NUMBER='(0,R2,0,0,0,0,0)';
      BIDIRECTIONAL='TRUE';
      INPUT_LOAD='(-0.01,0.01)';
      OUTPUT_LOAD='(1.0,-1.0)';
    'PL18B':
      PIN_NUMBER='(0,R3,0,0,0,0,0)';
      BIDIRECTIONAL='TRUE';
      INPUT_LOAD='(-0.01,0.01)';
      OUTPUT_LOAD='(1.0,-1.0)';
    'PL18C':
      PIN_NUMBER='(0,M3,0,0,0,0,0)';
      BIDIRECTIONAL='TRUE';
      INPUT_LOAD='(-0.01,0.01)';
      OUTPUT_LOAD='(1.0,-1.0)';
    'PL18D':
      PIN_NUMBER='(0,N5,0,0,0,0,0)';
      BIDIRECTIONAL='TRUE';
      INPUT_LOAD='(-0.01,0.01)';
      OUTPUT_LOAD='(1.0,-1.0)';
    'PL19A':
      PIN_NUMBER='(0,U3,0,0,0,0,0)';
      BIDIRECTIONAL='TRUE';
      INPUT_LOAD='(-0.01,0.01)';
      OUTPUT_LOAD='(1.0,-1.0)';
    'PL19B':
      PIN_NUMBER='(0,V1,0,0,0,0,0)';
      BIDIRECTIONAL='TRUE';
      INPUT_LOAD='(-0.01,0.01)';
      OUTPUT_LOAD='(1.0,-1.0)';
    'PL19C':
      PIN_NUMBER='(0,N7,0,0,0,0,0)';
      BIDIRECTIONAL='TRUE';
      INPUT_LOAD='(-0.01,0.01)';
      OUTPUT_LOAD='(1.0,-1.0)';
    'PL19D':
      PIN_NUMBER='(0,N6,0,0,0,0,0)';
      BIDIRECTIONAL='TRUE';
      INPUT_LOAD='(-0.01,0.01)';
      OUTPUT_LOAD='(1.0,-1.0)';
    'PL21A':
      PIN_NUMBER='(0,W1,0,0,0,0,0)';
      BIDIRECTIONAL='TRUE';
      INPUT_LOAD='(-0.01,0.01)';
      OUTPUT_LOAD='(1.0,-1.0)';
    'PL21B':
      PIN_NUMBER='(0,V2,0,0,0,0,0)';
      BIDIRECTIONAL='TRUE';
      INPUT_LOAD='(-0.01,0.01)';
      OUTPUT_LOAD='(1.0,-1.0)';
    'PL21C':
      PIN_NUMBER='(0,P7,0,0,0,0,0)';
      BIDIRECTIONAL='TRUE';
      INPUT_LOAD='(-0.01,0.01)';
      OUTPUT_LOAD='(1.0,-1.0)';
    'PL21D':
      PIN_NUMBER='(0,P6,0,0,0,0,0)';
      BIDIRECTIONAL='TRUE';
      INPUT_LOAD='(-0.01,0.01)';
      OUTPUT_LOAD='(1.0,-1.0)';
    'PL22A_PCLKT3_0':
      PIN_NUMBER='(0,V3,0,0,0,0,0)';
      BIDIRECTIONAL='TRUE';
      INPUT_LOAD='(-0.01,0.01)';
      OUTPUT_LOAD='(1.0,-1.0)';
    'PL22B_PCLKC3_0':
      PIN_NUMBER='(0,W2,0,0,0,0,0)';
      BIDIRECTIONAL='TRUE';
      INPUT_LOAD='(-0.01,0.01)';
      OUTPUT_LOAD='(1.0,-1.0)';
    'PL22C':
      PIN_NUMBER='(0,T4,0,0,0,0,0)';
      BIDIRECTIONAL='TRUE';
      INPUT_LOAD='(-0.01,0.01)';
      OUTPUT_LOAD='(1.0,-1.0)';
    'PL22D':
      PIN_NUMBER='(0,U4,0,0,0,0,0)';
      BIDIRECTIONAL='TRUE';
      INPUT_LOAD='(-0.01,0.01)';
      OUTPUT_LOAD='(1.0,-1.0)';
    'PL23A':
      PIN_NUMBER='(0,Y1,0,0,0,0,0)';
      BIDIRECTIONAL='TRUE';
      INPUT_LOAD='(-0.01,0.01)';
      OUTPUT_LOAD='(1.0,-1.0)';
    'PL23B':
      PIN_NUMBER='(0,AA1,0,0,0,0,0)';
      BIDIRECTIONAL='TRUE';
      INPUT_LOAD='(-0.01,0.01)';
      OUTPUT_LOAD='(1.0,-1.0)';
    'PL23C':
      PIN_NUMBER='(0,T5,0,0,0,0,0)';
      BIDIRECTIONAL='TRUE';
      INPUT_LOAD='(-0.01,0.01)';
      OUTPUT_LOAD='(1.0,-1.0)';
    'PL23D':
      PIN_NUMBER='(0,R6,0,0,0,0,0)';
      BIDIRECTIONAL='TRUE';
      INPUT_LOAD='(-0.01,0.01)';
      OUTPUT_LOAD='(1.0,-1.0)';
    'PL24A':
      PIN_NUMBER='(0,W3,0,0,0,0,0)';
      BIDIRECTIONAL='TRUE';
      INPUT_LOAD='(-0.01,0.01)';
      OUTPUT_LOAD='(1.0,-1.0)';
    'PL24B':
      PIN_NUMBER='(0,V4,0,0,0,0,0)';
      BIDIRECTIONAL='TRUE';
      INPUT_LOAD='(-0.01,0.01)';
      OUTPUT_LOAD='(1.0,-1.0)';
    'PL24C':
      PIN_NUMBER='(0,R7,0,0,0,0,0)';
      BIDIRECTIONAL='TRUE';
      INPUT_LOAD='(-0.01,0.01)';
      OUTPUT_LOAD='(1.0,-1.0)';
    'PL24D':
      PIN_NUMBER='(0,T6,0,0,0,0,0)';
      BIDIRECTIONAL='TRUE';
      INPUT_LOAD='(-0.01,0.01)';
      OUTPUT_LOAD='(1.0,-1.0)';
    'PL25A':
      PIN_NUMBER='(0,Y2,0,0,0,0,0)';
      BIDIRECTIONAL='TRUE';
      INPUT_LOAD='(-0.01,0.01)';
      OUTPUT_LOAD='(1.0,-1.0)';
    'PL25B':
      PIN_NUMBER='(0,W4,0,0,0,0,0)';
      BIDIRECTIONAL='TRUE';
      INPUT_LOAD='(-0.01,0.01)';
      OUTPUT_LOAD='(1.0,-1.0)';
    'PL25C':
      PIN_NUMBER='(0,U5,0,0,0,0,0)';
      BIDIRECTIONAL='TRUE';
      INPUT_LOAD='(-0.01,0.01)';
      OUTPUT_LOAD='(1.0,-1.0)';
    'PL25D':
      PIN_NUMBER='(0,T7,0,0,0,0,0)';
      BIDIRECTIONAL='TRUE';
      INPUT_LOAD='(-0.01,0.01)';
      OUTPUT_LOAD='(1.0,-1.0)';
    'PL2A':
      PIN_NUMBER='(0,C3,0,0,0,0,0)';
      BIDIRECTIONAL='TRUE';
      INPUT_LOAD='(-0.01,0.01)';
      OUTPUT_LOAD='(1.0,-1.0)';
    'PL2B':
      PIN_NUMBER='(0,C2,0,0,0,0,0)';
      BIDIRECTIONAL='TRUE';
      INPUT_LOAD='(-0.01,0.01)';
      OUTPUT_LOAD='(1.0,-1.0)';
    'PL2C':
      PIN_NUMBER='(0,F6,0,0,0,0,0)';
      BIDIRECTIONAL='TRUE';
      INPUT_LOAD='(-0.01,0.01)';
      OUTPUT_LOAD='(1.0,-1.0)';
    'PL2D':
      PIN_NUMBER='(0,F5,0,0,0,0,0)';
      BIDIRECTIONAL='TRUE';
      INPUT_LOAD='(-0.01,0.01)';
      OUTPUT_LOAD='(1.0,-1.0)';
    'PL3A_L_GPLLT_FB':
      PIN_NUMBER='(0,E4,0,0,0,0,0)';
      BIDIRECTIONAL='TRUE';
      INPUT_LOAD='(-0.01,0.01)';
      OUTPUT_LOAD='(1.0,-1.0)';
    'PL3B_L_GPLLC_FB':
      PIN_NUMBER='(0,D3,0,0,0,0,0)';
      BIDIRECTIONAL='TRUE';
      INPUT_LOAD='(-0.01,0.01)';
      OUTPUT_LOAD='(1.0,-1.0)';
    'PL3C':
      PIN_NUMBER='(0,G6,0,0,0,0,0)';
      BIDIRECTIONAL='TRUE';
      INPUT_LOAD='(-0.01,0.01)';
      OUTPUT_LOAD='(1.0,-1.0)';
    'PL3D':
      PIN_NUMBER='(0,H7,0,0,0,0,0)';
      BIDIRECTIONAL='TRUE';
      INPUT_LOAD='(-0.01,0.01)';
      OUTPUT_LOAD='(1.0,-1.0)';
    'PL4A_L_GPLLT_IN':
      PIN_NUMBER='(0,B1,0,0,0,0,0)';
      BIDIRECTIONAL='TRUE';
      INPUT_LOAD='(-0.01,0.01)';
      OUTPUT_LOAD='(1.0,-1.0)';
    'PL4B_L_GPLLC_IN':
      PIN_NUMBER='(0,C1,0,0,0,0,0)';
      BIDIRECTIONAL='TRUE';
      INPUT_LOAD='(-0.01,0.01)';
      OUTPUT_LOAD='(1.0,-1.0)';
    'PL4C':
      PIN_NUMBER='(0,H6,0,0,0,0,0)';
      BIDIRECTIONAL='TRUE';
      INPUT_LOAD='(-0.01,0.01)';
      OUTPUT_LOAD='(1.0,-1.0)';
    'PL4D':
      PIN_NUMBER='(0,G5,0,0,0,0,0)';
      BIDIRECTIONAL='TRUE';
      INPUT_LOAD='(-0.01,0.01)';
      OUTPUT_LOAD='(1.0,-1.0)';
    'PL5A':
      PIN_NUMBER='(0,E2,0,0,0,0,0)';
      BIDIRECTIONAL='TRUE';
      INPUT_LOAD='(-0.01,0.01)';
      OUTPUT_LOAD='(1.0,-1.0)';
    'PL5B':
      PIN_NUMBER='(0,D1,0,0,0,0,0)';
      BIDIRECTIONAL='TRUE';
      INPUT_LOAD='(-0.01,0.01)';
      OUTPUT_LOAD='(1.0,-1.0)';
    'PL5C':
      PIN_NUMBER='(0,F4,0,0,0,0,0)';
      BIDIRECTIONAL='TRUE';
      INPUT_LOAD='(-0.01,0.01)';
      OUTPUT_LOAD='(1.0,-1.0)';
    'PL5D':
      PIN_NUMBER='(0,G4,0,0,0,0,0)';
      BIDIRECTIONAL='TRUE';
      INPUT_LOAD='(-0.01,0.01)';
      OUTPUT_LOAD='(1.0,-1.0)';
    'PL6A_PCLKT5_0':
      PIN_NUMBER='(0,E1,0,0,0,0,0)';
      BIDIRECTIONAL='TRUE';
      INPUT_LOAD='(-0.01,0.01)';
      OUTPUT_LOAD='(1.0,-1.0)';
    'PL6B_PCLKC5_0':
      PIN_NUMBER='(0,F3,0,0,0,0,0)';
      BIDIRECTIONAL='TRUE';
      INPUT_LOAD='(-0.01,0.01)';
      OUTPUT_LOAD='(1.0,-1.0)';
    'PL6C':
      PIN_NUMBER='(0,H5,0,0,0,0,0)';
      BIDIRECTIONAL='TRUE';
      INPUT_LOAD='(-0.01,0.01)';
      OUTPUT_LOAD='(1.0,-1.0)';
    'PL6D':
      PIN_NUMBER='(0,H4,0,0,0,0,0)';
      BIDIRECTIONAL='TRUE';
      INPUT_LOAD='(-0.01,0.01)';
      OUTPUT_LOAD='(1.0,-1.0)';
    'PL7A':
      PIN_NUMBER='(0,F1,0,0,0,0,0)';
      BIDIRECTIONAL='TRUE';
      INPUT_LOAD='(-0.01,0.01)';
      OUTPUT_LOAD='(1.0,-1.0)';
    'PL7B':
      PIN_NUMBER='(0,G3,0,0,0,0,0)';
      BIDIRECTIONAL='TRUE';
      INPUT_LOAD='(-0.01,0.01)';
      OUTPUT_LOAD='(1.0,-1.0)';
    'PL7C':
      PIN_NUMBER='(0,J5,0,0,0,0,0)';
      BIDIRECTIONAL='TRUE';
      INPUT_LOAD='(-0.01,0.01)';
      OUTPUT_LOAD='(1.0,-1.0)';
    'PL7D':
      PIN_NUMBER='(0,J4,0,0,0,0,0)';
      BIDIRECTIONAL='TRUE';
      INPUT_LOAD='(-0.01,0.01)';
      OUTPUT_LOAD='(1.0,-1.0)';
    'PL8A':
      PIN_NUMBER='(0,G2,0,0,0,0,0)';
      BIDIRECTIONAL='TRUE';
      INPUT_LOAD='(-0.01,0.01)';
      OUTPUT_LOAD='(1.0,-1.0)';
    'PL8B':
      PIN_NUMBER='(0,G1,0,0,0,0,0)';
      BIDIRECTIONAL='TRUE';
      INPUT_LOAD='(-0.01,0.01)';
      OUTPUT_LOAD='(1.0,-1.0)';
    'PL8C':
      PIN_NUMBER='(0,K6,0,0,0,0,0)';
      BIDIRECTIONAL='TRUE';
      INPUT_LOAD='(-0.01,0.01)';
      OUTPUT_LOAD='(1.0,-1.0)';
    'PL8D':
      PIN_NUMBER='(0,K7,0,0,0,0,0)';
      BIDIRECTIONAL='TRUE';
      INPUT_LOAD='(-0.01,0.01)';
      OUTPUT_LOAD='(1.0,-1.0)';
    'PL9A':
      PIN_NUMBER='(0,H3,0,0,0,0,0)';
      BIDIRECTIONAL='TRUE';
      INPUT_LOAD='(-0.01,0.01)';
      OUTPUT_LOAD='(1.0,-1.0)';
    'PL9B':
      PIN_NUMBER='(0,H2,0,0,0,0,0)';
      BIDIRECTIONAL='TRUE';
      INPUT_LOAD='(-0.01,0.01)';
      OUTPUT_LOAD='(1.0,-1.0)';
    'PL9C':
      PIN_NUMBER='(0,K5,0,0,0,0,0)';
      BIDIRECTIONAL='TRUE';
      INPUT_LOAD='(-0.01,0.01)';
      OUTPUT_LOAD='(1.0,-1.0)';
    'PL9D':
      PIN_NUMBER='(0,L3,0,0,0,0,0)';
      BIDIRECTIONAL='TRUE';
      INPUT_LOAD='(-0.01,0.01)';
      OUTPUT_LOAD='(1.0,-1.0)';
    'PR10A':
      PIN_NUMBER='(0,0,J21,0,0,0,0)';
      BIDIRECTIONAL='TRUE';
      INPUT_LOAD='(-0.01,0.01)';
      OUTPUT_LOAD='(1.0,-1.0)';
    'PR10B':
      PIN_NUMBER='(0,0,K20,0,0,0,0)';
      BIDIRECTIONAL='TRUE';
      INPUT_LOAD='(-0.01,0.01)';
      OUTPUT_LOAD='(1.0,-1.0)';
    'PR10C':
      PIN_NUMBER='(0,0,L17,0,0,0,0)';
      BIDIRECTIONAL='TRUE';
      INPUT_LOAD='(-0.01,0.01)';
      OUTPUT_LOAD='(1.0,-1.0)';
    'PR10D':
      PIN_NUMBER='(0,0,L16,0,0,0,0)';
      BIDIRECTIONAL='TRUE';
      INPUT_LOAD='(-0.01,0.01)';
      OUTPUT_LOAD='(1.0,-1.0)';
    'PR11A':
      PIN_NUMBER='(0,0,K21,0,0,0,0)';
      BIDIRECTIONAL='TRUE';
      INPUT_LOAD='(-0.01,0.01)';
      OUTPUT_LOAD='(1.0,-1.0)';
    'PR11B':
      PIN_NUMBER='(0,0,K22,0,0,0,0)';
      BIDIRECTIONAL='TRUE';
      INPUT_LOAD='(-0.01,0.01)';
      OUTPUT_LOAD='(1.0,-1.0)';
    'PR11C':
      PIN_NUMBER='(0,0,L21,0,0,0,0)';
      BIDIRECTIONAL='TRUE';
      INPUT_LOAD='(-0.01,0.01)';
      OUTPUT_LOAD='(1.0,-1.0)';
    'PR11D':
      PIN_NUMBER='(0,0,L22,0,0,0,0)';
      BIDIRECTIONAL='TRUE';
      INPUT_LOAD='(-0.01,0.01)';
      OUTPUT_LOAD='(1.0,-1.0)';
    'PR12A':
      PIN_NUMBER='(0,0,N22,0,0,0,0)';
      BIDIRECTIONAL='TRUE';
      INPUT_LOAD='(-0.01,0.01)';
      OUTPUT_LOAD='(1.0,-1.0)';
    'PR12B':
      PIN_NUMBER='(0,0,N21,0,0,0,0)';
      BIDIRECTIONAL='TRUE';
      INPUT_LOAD='(-0.01,0.01)';
      OUTPUT_LOAD='(1.0,-1.0)';
    'PR12C':
      PIN_NUMBER='(0,0,M22,0,0,0,0)';
      BIDIRECTIONAL='TRUE';
      INPUT_LOAD='(-0.01,0.01)';
      OUTPUT_LOAD='(1.0,-1.0)';
    'PR12D':
      PIN_NUMBER='(0,0,M21,0,0,0,0)';
      BIDIRECTIONAL='TRUE';
      INPUT_LOAD='(-0.01,0.01)';
      OUTPUT_LOAD='(1.0,-1.0)';
    'PR15A':
      PIN_NUMBER='(0,0,N20,0,0,0,0)';
      BIDIRECTIONAL='TRUE';
      INPUT_LOAD='(-0.01,0.01)';
      OUTPUT_LOAD='(1.0,-1.0)';
    'PR15B':
      PIN_NUMBER='(0,0,P21,0,0,0,0)';
      BIDIRECTIONAL='TRUE';
      INPUT_LOAD='(-0.01,0.01)';
      OUTPUT_LOAD='(1.0,-1.0)';
    'PR15C':
      PIN_NUMBER='(0,0,M16,0,0,0,0)';
      BIDIRECTIONAL='TRUE';
      INPUT_LOAD='(-0.01,0.01)';
      OUTPUT_LOAD='(1.0,-1.0)';
    'PR15D':
      PIN_NUMBER='(0,0,M17,0,0,0,0)';
      BIDIRECTIONAL='TRUE';
      INPUT_LOAD='(-0.01,0.01)';
      OUTPUT_LOAD='(1.0,-1.0)';
    'PR16A':
      PIN_NUMBER='(0,0,P20,0,0,0,0)';
      BIDIRECTIONAL='TRUE';
      INPUT_LOAD='(-0.01,0.01)';
      OUTPUT_LOAD='(1.0,-1.0)';
    'PR16B':
      PIN_NUMBER='(0,0,R22,0,0,0,0)';
      BIDIRECTIONAL='TRUE';
      INPUT_LOAD='(-0.01,0.01)';
      OUTPUT_LOAD='(1.0,-1.0)';
    'PR16C':
      PIN_NUMBER='(0,0,M19,0,0,0,0)';
      BIDIRECTIONAL='TRUE';
      INPUT_LOAD='(-0.01,0.01)';
      OUTPUT_LOAD='(1.0,-1.0)';
    'PR16D':
      PIN_NUMBER='(0,0,M18,0,0,0,0)';
      BIDIRECTIONAL='TRUE';
      INPUT_LOAD='(-0.01,0.01)';
      OUTPUT_LOAD='(1.0,-1.0)';
    'PR17A':
      PIN_NUMBER='(0,0,R21,0,0,0,0)';
      BIDIRECTIONAL='TRUE';
      INPUT_LOAD='(-0.01,0.01)';
      OUTPUT_LOAD='(1.0,-1.0)';
    'PR17B':
      PIN_NUMBER='(0,0,R20,0,0,0,0)';
      BIDIRECTIONAL='TRUE';
      INPUT_LOAD='(-0.01,0.01)';
      OUTPUT_LOAD='(1.0,-1.0)';
    'PR17C':
      PIN_NUMBER='(0,0,M20,0,0,0,0)';
      BIDIRECTIONAL='TRUE';
      INPUT_LOAD='(-0.01,0.01)';
      OUTPUT_LOAD='(1.0,-1.0)';
    'PR17D':
      PIN_NUMBER='(0,0,N18,0,0,0,0)';
      BIDIRECTIONAL='TRUE';
      INPUT_LOAD='(-0.01,0.01)';
      OUTPUT_LOAD='(1.0,-1.0)';
    'PR18A':
      PIN_NUMBER='(0,0,T22,0,0,0,0)';
      BIDIRECTIONAL='TRUE';
      INPUT_LOAD='(-0.01,0.01)';
      OUTPUT_LOAD='(1.0,-1.0)';
    'PR18B':
      PIN_NUMBER='(0,0,T21,0,0,0,0)';
      BIDIRECTIONAL='TRUE';
      INPUT_LOAD='(-0.01,0.01)';
      OUTPUT_LOAD='(1.0,-1.0)';
    'PR18C':
      PIN_NUMBER='(0,0,N16,0,0,0,0)';
      BIDIRECTIONAL='TRUE';
      INPUT_LOAD='(-0.01,0.01)';
      OUTPUT_LOAD='(1.0,-1.0)';
    'PR18D':
      PIN_NUMBER='(0,0,N17,0,0,0,0)';
      BIDIRECTIONAL='TRUE';
      INPUT_LOAD='(-0.01,0.01)';
      OUTPUT_LOAD='(1.0,-1.0)';
    'PR19A':
      PIN_NUMBER='(0,0,T20,0,0,0,0)';
      BIDIRECTIONAL='TRUE';
      INPUT_LOAD='(-0.01,0.01)';
      OUTPUT_LOAD='(1.0,-1.0)';
    'PR19B':
      PIN_NUMBER='(0,0,U22,0,0,0,0)';
      BIDIRECTIONAL='TRUE';
      INPUT_LOAD='(-0.01,0.01)';
      OUTPUT_LOAD='(1.0,-1.0)';
    'PR19C':
      PIN_NUMBER='(0,0,P19,0,0,0,0)';
      BIDIRECTIONAL='TRUE';
      INPUT_LOAD='(-0.01,0.01)';
      OUTPUT_LOAD='(1.0,-1.0)';
    'PR19D':
      PIN_NUMBER='(0,0,P18,0,0,0,0)';
      BIDIRECTIONAL='TRUE';
      INPUT_LOAD='(-0.01,0.01)';
      OUTPUT_LOAD='(1.0,-1.0)';
    'PR21A':
      PIN_NUMBER='(0,0,U20,0,0,0,0)';
      BIDIRECTIONAL='TRUE';
      INPUT_LOAD='(-0.01,0.01)';
      OUTPUT_LOAD='(1.0,-1.0)';
    'PR21B':
      PIN_NUMBER='(0,0,V22,0,0,0,0)';
      BIDIRECTIONAL='TRUE';
      INPUT_LOAD='(-0.01,0.01)';
      OUTPUT_LOAD='(1.0,-1.0)';
    'PR21C':
      PIN_NUMBER='(0,0,R19,0,0,0,0)';
      BIDIRECTIONAL='TRUE';
      INPUT_LOAD='(-0.01,0.01)';
      OUTPUT_LOAD='(1.0,-1.0)';
    'PR21D':
      PIN_NUMBER='(0,0,R18,0,0,0,0)';
      BIDIRECTIONAL='TRUE';
      INPUT_LOAD='(-0.01,0.01)';
      OUTPUT_LOAD='(1.0,-1.0)';
    'PR22A':
      PIN_NUMBER='(0,0,W22,0,0,0,0)';
      BIDIRECTIONAL='TRUE';
      INPUT_LOAD='(-0.01,0.01)';
      OUTPUT_LOAD='(1.0,-1.0)';
    'PR22B':
      PIN_NUMBER='(0,0,V21,0,0,0,0)';
      BIDIRECTIONAL='TRUE';
      INPUT_LOAD='(-0.01,0.01)';
      OUTPUT_LOAD='(1.0,-1.0)';
    'PR22C':
      PIN_NUMBER='(0,0,T19,0,0,0,0)';
      BIDIRECTIONAL='TRUE';
      INPUT_LOAD='(-0.01,0.01)';
      OUTPUT_LOAD='(1.0,-1.0)';
    'PR22D':
      PIN_NUMBER='(0,0,U19,0,0,0,0)';
      BIDIRECTIONAL='TRUE';
      INPUT_LOAD='(-0.01,0.01)';
      OUTPUT_LOAD='(1.0,-1.0)';
    'PR23A':
      PIN_NUMBER='(0,0,Y22,0,0,0,0)';
      BIDIRECTIONAL='TRUE';
      INPUT_LOAD='(-0.01,0.01)';
      OUTPUT_LOAD='(1.0,-1.0)';
    'PR23B':
      PIN_NUMBER='(0,0,AA22,0,0,0,0)';
      BIDIRECTIONAL='TRUE';
      INPUT_LOAD='(-0.01,0.01)';
      OUTPUT_LOAD='(1.0,-1.0)';
    'PR23C':
      PIN_NUMBER='(0,0,T18,0,0,0,0)';
      BIDIRECTIONAL='TRUE';
      INPUT_LOAD='(-0.01,0.01)';
      OUTPUT_LOAD='(1.0,-1.0)';
    'PR23D':
      PIN_NUMBER='(0,0,R17,0,0,0,0)';
      BIDIRECTIONAL='TRUE';
      INPUT_LOAD='(-0.01,0.01)';
      OUTPUT_LOAD='(1.0,-1.0)';
    'PR24A':
      PIN_NUMBER='(0,0,W20,0,0,0,0)';
      BIDIRECTIONAL='TRUE';
      INPUT_LOAD='(-0.01,0.01)';
      OUTPUT_LOAD='(1.0,-1.0)';
    'PR24B':
      PIN_NUMBER='(0,0,V19,0,0,0,0)';
      BIDIRECTIONAL='TRUE';
      INPUT_LOAD='(-0.01,0.01)';
      OUTPUT_LOAD='(1.0,-1.0)';
    'PR24C':
      PIN_NUMBER='(0,0,R16,0,0,0,0)';
      BIDIRECTIONAL='TRUE';
      INPUT_LOAD='(-0.01,0.01)';
      OUTPUT_LOAD='(1.0,-1.0)';
    'PR24D':
      PIN_NUMBER='(0,0,T17,0,0,0,0)';
      BIDIRECTIONAL='TRUE';
      INPUT_LOAD='(-0.01,0.01)';
      OUTPUT_LOAD='(1.0,-1.0)';
    'PR25A':
      PIN_NUMBER='(0,0,Y21,0,0,0,0)';
      BIDIRECTIONAL='TRUE';
      INPUT_LOAD='(-0.01,0.01)';
      OUTPUT_LOAD='(1.0,-1.0)';
    'PR25B':
      PIN_NUMBER='(0,0,Y20,0,0,0,0)';
      BIDIRECTIONAL='TRUE';
      INPUT_LOAD='(-0.01,0.01)';
      OUTPUT_LOAD='(1.0,-1.0)';
    'PR25C':
      PIN_NUMBER='(0,0,U18,0,0,0,0)';
      BIDIRECTIONAL='TRUE';
      INPUT_LOAD='(-0.01,0.01)';
      OUTPUT_LOAD='(1.0,-1.0)';
    'PR25D':
      PIN_NUMBER='(0,0,U17,0,0,0,0)';
      BIDIRECTIONAL='TRUE';
      INPUT_LOAD='(-0.01,0.01)';
      OUTPUT_LOAD='(1.0,-1.0)';
    'PR2A_R_GPLLT_FB':
      PIN_NUMBER='(0,0,D19,0,0,0,0)';
      BIDIRECTIONAL='TRUE';
      INPUT_LOAD='(-0.01,0.01)';
      OUTPUT_LOAD='(1.0,-1.0)';
    'PR2B_R_GPLLC_FB':
      PIN_NUMBER='(0,0,C21,0,0,0,0)';
      BIDIRECTIONAL='TRUE';
      INPUT_LOAD='(-0.01,0.01)';
      OUTPUT_LOAD='(1.0,-1.0)';
    'PR2C':
      PIN_NUMBER='(0,0,G16,0,0,0,0)';
      BIDIRECTIONAL='TRUE';
      INPUT_LOAD='(-0.01,0.01)';
      OUTPUT_LOAD='(1.0,-1.0)';
    'PR2D':
      PIN_NUMBER='(0,0,F18,0,0,0,0)';
      BIDIRECTIONAL='TRUE';
      INPUT_LOAD='(-0.01,0.01)';
      OUTPUT_LOAD='(1.0,-1.0)';
    'PR3A_R_GPLLT_IN':
      PIN_NUMBER='(0,0,E19,0,0,0,0)';
      BIDIRECTIONAL='TRUE';
      INPUT_LOAD='(-0.01,0.01)';
      OUTPUT_LOAD='(1.0,-1.0)';
    'PR3B_R_GPLLC_IN':
      PIN_NUMBER='(0,0,D20,0,0,0,0)';
      BIDIRECTIONAL='TRUE';
      INPUT_LOAD='(-0.01,0.01)';
      OUTPUT_LOAD='(1.0,-1.0)';
    'PR3C':
      PIN_NUMBER='(0,0,G17,0,0,0,0)';
      BIDIRECTIONAL='TRUE';
      INPUT_LOAD='(-0.01,0.01)';
      OUTPUT_LOAD='(1.0,-1.0)';
    'PR3D':
      PIN_NUMBER='(0,0,H16,0,0,0,0)';
      BIDIRECTIONAL='TRUE';
      INPUT_LOAD='(-0.01,0.01)';
      OUTPUT_LOAD='(1.0,-1.0)';
    'PR4A':
      PIN_NUMBER='(0,0,B22,0,0,0,0)';
      BIDIRECTIONAL='TRUE';
      INPUT_LOAD='(-0.01,0.01)';
      OUTPUT_LOAD='(1.0,-1.0)';
    'PR4B':
      PIN_NUMBER='(0,0,C22,0,0,0,0)';
      BIDIRECTIONAL='TRUE';
      INPUT_LOAD='(-0.01,0.01)';
      OUTPUT_LOAD='(1.0,-1.0)';
    'PR4C':
      PIN_NUMBER='(0,0,H17,0,0,0,0)';
      BIDIRECTIONAL='TRUE';
      INPUT_LOAD='(-0.01,0.01)';
      OUTPUT_LOAD='(1.0,-1.0)';
    'PR4D':
      PIN_NUMBER='(0,0,G18,0,0,0,0)';
      BIDIRECTIONAL='TRUE';
      INPUT_LOAD='(-0.01,0.01)';
      OUTPUT_LOAD='(1.0,-1.0)';
    'PR5A':
      PIN_NUMBER='(0,0,D21,0,0,0,0)';
      BIDIRECTIONAL='TRUE';
      INPUT_LOAD='(-0.01,0.01)';
      OUTPUT_LOAD='(1.0,-1.0)';
    'PR5B':
      PIN_NUMBER='(0,0,E20,0,0,0,0)';
      BIDIRECTIONAL='TRUE';
      INPUT_LOAD='(-0.01,0.01)';
      OUTPUT_LOAD='(1.0,-1.0)';
    'PR5C':
      PIN_NUMBER='(0,0,F19,0,0,0,0)';
      BIDIRECTIONAL='TRUE';
      INPUT_LOAD='(-0.01,0.01)';
      OUTPUT_LOAD='(1.0,-1.0)';
    'PR5D':
      PIN_NUMBER='(0,0,G19,0,0,0,0)';
      BIDIRECTIONAL='TRUE';
      INPUT_LOAD='(-0.01,0.01)';
      OUTPUT_LOAD='(1.0,-1.0)';
    'PR6A':
      PIN_NUMBER='(0,0,E21,0,0,0,0)';
      BIDIRECTIONAL='TRUE';
      INPUT_LOAD='(-0.01,0.01)';
      OUTPUT_LOAD='(1.0,-1.0)';
    'PR6B':
      PIN_NUMBER='(0,0,D22,0,0,0,0)';
      BIDIRECTIONAL='TRUE';
      INPUT_LOAD='(-0.01,0.01)';
      OUTPUT_LOAD='(1.0,-1.0)';
    'PR6C':
      PIN_NUMBER='(0,0,J17,0,0,0,0)';
      BIDIRECTIONAL='TRUE';
      INPUT_LOAD='(-0.01,0.01)';
      OUTPUT_LOAD='(1.0,-1.0)';
    'PR6D':
      PIN_NUMBER='(0,0,J16,0,0,0,0)';
      BIDIRECTIONAL='TRUE';
      INPUT_LOAD='(-0.01,0.01)';
      OUTPUT_LOAD='(1.0,-1.0)';
    'PR7A':
      PIN_NUMBER='(0,0,E22,0,0,0,0)';
      BIDIRECTIONAL='TRUE';
      INPUT_LOAD='(-0.01,0.01)';
      OUTPUT_LOAD='(1.0,-1.0)';
    'PR7B':
      PIN_NUMBER='(0,0,F20,0,0,0,0)';
      BIDIRECTIONAL='TRUE';
      INPUT_LOAD='(-0.01,0.01)';
      OUTPUT_LOAD='(1.0,-1.0)';
    'PR7C':
      PIN_NUMBER='(0,0,J18,0,0,0,0)';
      BIDIRECTIONAL='TRUE';
      INPUT_LOAD='(-0.01,0.01)';
      OUTPUT_LOAD='(1.0,-1.0)';
    'PR7D':
      PIN_NUMBER='(0,0,J19,0,0,0,0)';
      BIDIRECTIONAL='TRUE';
      INPUT_LOAD='(-0.01,0.01)';
      OUTPUT_LOAD='(1.0,-1.0)';
    'PR8A':
      PIN_NUMBER='(0,0,G21,0,0,0,0)';
      BIDIRECTIONAL='TRUE';
      INPUT_LOAD='(-0.01,0.01)';
      OUTPUT_LOAD='(1.0,-1.0)';
    'PR8B':
      PIN_NUMBER='(0,0,G22,0,0,0,0)';
      BIDIRECTIONAL='TRUE';
      INPUT_LOAD='(-0.01,0.01)';
      OUTPUT_LOAD='(1.0,-1.0)';
    'PR8C':
      PIN_NUMBER='(0,0,K17,0,0,0,0)';
      BIDIRECTIONAL='TRUE';
      INPUT_LOAD='(-0.01,0.01)';
      OUTPUT_LOAD='(1.0,-1.0)';
    'PR8D':
      PIN_NUMBER='(0,0,K16,0,0,0,0)';
      BIDIRECTIONAL='TRUE';
      INPUT_LOAD='(-0.01,0.01)';
      OUTPUT_LOAD='(1.0,-1.0)';
    'PR9A':
      PIN_NUMBER='(0,0,H20,0,0,0,0)';
      BIDIRECTIONAL='TRUE';
      INPUT_LOAD='(-0.01,0.01)';
      OUTPUT_LOAD='(1.0,-1.0)';
    'PR9B':
      PIN_NUMBER='(0,0,H21,0,0,0,0)';
      BIDIRECTIONAL='TRUE';
      INPUT_LOAD='(-0.01,0.01)';
      OUTPUT_LOAD='(1.0,-1.0)';
    'PR9C':
      PIN_NUMBER='(0,0,K18,0,0,0,0)';
      BIDIRECTIONAL='TRUE';
      INPUT_LOAD='(-0.01,0.01)';
      OUTPUT_LOAD='(1.0,-1.0)';
    'PR9D':
      PIN_NUMBER='(0,0,L20,0,0,0,0)';
      BIDIRECTIONAL='TRUE';
      INPUT_LOAD='(-0.01,0.01)';
      OUTPUT_LOAD='(1.0,-1.0)';
    'PT10A':
      PIN_NUMBER='(0,0,0,D5,0,0,0)';
      BIDIRECTIONAL='TRUE';
      INPUT_LOAD='(-0.01,0.01)';
      OUTPUT_LOAD='(1.0,-1.0)';
    'PT10B':
      PIN_NUMBER='(0,0,0,C4,0,0,0)';
      BIDIRECTIONAL='TRUE';
      INPUT_LOAD='(-0.01,0.01)';
      OUTPUT_LOAD='(1.0,-1.0)';
    'PT10D':
      PIN_NUMBER='(0,0,0,G8,0,0,0)';
      BIDIRECTIONAL='TRUE';
      INPUT_LOAD='(-0.01,0.01)';
      OUTPUT_LOAD='(1.0,-1.0)';
    'PT11A':
      PIN_NUMBER='(0,0,0,A2,0,0,0)';
      BIDIRECTIONAL='TRUE';
      INPUT_LOAD='(-0.01,0.01)';
      OUTPUT_LOAD='(1.0,-1.0)';
    'PT11B':
      PIN_NUMBER='(0,0,0,A3,0,0,0)';
      BIDIRECTIONAL='TRUE';
      INPUT_LOAD='(-0.01,0.01)';
      OUTPUT_LOAD='(1.0,-1.0)';
    'PT11C':
      PIN_NUMBER='(0,0,0,F8,0,0,0)';
      BIDIRECTIONAL='TRUE';
      INPUT_LOAD='(-0.01,0.01)';
      OUTPUT_LOAD='(1.0,-1.0)';
    'PT11D':
      PIN_NUMBER='(0,0,0,E7,0,0,0)';
      BIDIRECTIONAL='TRUE';
      INPUT_LOAD='(-0.01,0.01)';
      OUTPUT_LOAD='(1.0,-1.0)';
    'PT12A':
      PIN_NUMBER='(0,0,0,D6,0,0,0)';
      BIDIRECTIONAL='TRUE';
      INPUT_LOAD='(-0.01,0.01)';
      OUTPUT_LOAD='(1.0,-1.0)';
    'PT12B':
      PIN_NUMBER='(0,0,0,D7,0,0,0)';
      BIDIRECTIONAL='TRUE';
      INPUT_LOAD='(-0.01,0.01)';
      OUTPUT_LOAD='(1.0,-1.0)';
    'PT12C':
      PIN_NUMBER='(0,0,0,B4,0,0,0)';
      BIDIRECTIONAL='TRUE';
      INPUT_LOAD='(-0.01,0.01)';
      OUTPUT_LOAD='(1.0,-1.0)';
    'PT12D':
      PIN_NUMBER='(0,0,0,C5,0,0,0)';
      BIDIRECTIONAL='TRUE';
      INPUT_LOAD='(-0.01,0.01)';
      OUTPUT_LOAD='(1.0,-1.0)';
    'PT13A':
      PIN_NUMBER='(0,0,0,A5,0,0,0)';
      BIDIRECTIONAL='TRUE';
      INPUT_LOAD='(-0.01,0.01)';
      OUTPUT_LOAD='(1.0,-1.0)';
    'PT13B':
      PIN_NUMBER='(0,0,0,C6,0,0,0)';
      BIDIRECTIONAL='TRUE';
      INPUT_LOAD='(-0.01,0.01)';
      OUTPUT_LOAD='(1.0,-1.0)';
    'PT13C':
      PIN_NUMBER='(0,0,0,E8,0,0,0)';
      BIDIRECTIONAL='TRUE';
      INPUT_LOAD='(-0.01,0.01)';
      OUTPUT_LOAD='(1.0,-1.0)';
    'PT13D':
      PIN_NUMBER='(0,0,0,D8,0,0,0)';
      BIDIRECTIONAL='TRUE';
      INPUT_LOAD='(-0.01,0.01)';
      OUTPUT_LOAD='(1.0,-1.0)';
    'PT14A':
      PIN_NUMBER='(0,0,0,E9,0,0,0)';
      BIDIRECTIONAL='TRUE';
      INPUT_LOAD='(-0.01,0.01)';
      OUTPUT_LOAD='(1.0,-1.0)';
    'PT14B':
      PIN_NUMBER='(0,0,0,D9,0,0,0)';
      BIDIRECTIONAL='TRUE';
      INPUT_LOAD='(-0.01,0.01)';
      OUTPUT_LOAD='(1.0,-1.0)';
    'PT14C_TDO':
      PIN_NUMBER='(0,0,0,A6,0,0,0)';
      BIDIRECTIONAL='TRUE';
      INPUT_LOAD='(-0.01,0.01)';
      OUTPUT_LOAD='(1.0,-1.0)';
    'PT14D_TDI':
      PIN_NUMBER='(0,0,0,C7,0,0,0)';
      BIDIRECTIONAL='TRUE';
      INPUT_LOAD='(-0.01,0.01)';
      OUTPUT_LOAD='(1.0,-1.0)';
    'PT15A':
      PIN_NUMBER='(0,0,0,B7,0,0,0)';
      BIDIRECTIONAL='TRUE';
      INPUT_LOAD='(-0.01,0.01)';
      OUTPUT_LOAD='(1.0,-1.0)';
    'PT15B':
      PIN_NUMBER='(0,0,0,A7,0,0,0)';
      BIDIRECTIONAL='TRUE';
      INPUT_LOAD='(-0.01,0.01)';
      OUTPUT_LOAD='(1.0,-1.0)';
    'PT15C':
      PIN_NUMBER='(0,0,0,F10,0,0,0)';
      BIDIRECTIONAL='TRUE';
      INPUT_LOAD='(-0.01,0.01)';
      OUTPUT_LOAD='(1.0,-1.0)';
    'PT15D':
      PIN_NUMBER='(0,0,0,G10,0,0,0)';
      BIDIRECTIONAL='TRUE';
      INPUT_LOAD='(-0.01,0.01)';
      OUTPUT_LOAD='(1.0,-1.0)';
    'PT16A':
      PIN_NUMBER='(0,0,0,E10,0,0,0)';
      BIDIRECTIONAL='TRUE';
      INPUT_LOAD='(-0.01,0.01)';
      OUTPUT_LOAD='(1.0,-1.0)';
    'PT16B':
      PIN_NUMBER='(0,0,0,C11,0,0,0)';
      BIDIRECTIONAL='TRUE';
      INPUT_LOAD='(-0.01,0.01)';
      OUTPUT_LOAD='(1.0,-1.0)';
    'PT16C':
      PIN_NUMBER='(0,0,0,C8,0,0,0)';
      BIDIRECTIONAL='TRUE';
      INPUT_LOAD='(-0.01,0.01)';
      OUTPUT_LOAD='(1.0,-1.0)';
    'PT16D':
      PIN_NUMBER='(0,0,0,B8,0,0,0)';
      BIDIRECTIONAL='TRUE';
      INPUT_LOAD='(-0.01,0.01)';
      OUTPUT_LOAD='(1.0,-1.0)';
    'PT17A':
      PIN_NUMBER='(0,0,0,E11,0,0,0)';
      BIDIRECTIONAL='TRUE';
      INPUT_LOAD='(-0.01,0.01)';
      OUTPUT_LOAD='(1.0,-1.0)';
    'PT17B':
      PIN_NUMBER='(0,0,0,D11,0,0,0)';
      BIDIRECTIONAL='TRUE';
      INPUT_LOAD='(-0.01,0.01)';
      OUTPUT_LOAD='(1.0,-1.0)';
    'PT17C_TCK':
      PIN_NUMBER='(0,0,0,A8,0,0,0)';
      BIDIRECTIONAL='TRUE';
      INPUT_LOAD='(-0.01,0.01)';
      OUTPUT_LOAD='(1.0,-1.0)';
    'PT17D_TMS':
      PIN_NUMBER='(0,0,0,C9,0,0,0)';
      BIDIRECTIONAL='TRUE';
      INPUT_LOAD='(-0.01,0.01)';
      OUTPUT_LOAD='(1.0,-1.0)';
    'PT18A_PCLKT0_1':
      PIN_NUMBER='(0,0,0,B9,0,0,0)';
      BIDIRECTIONAL='TRUE';
      INPUT_LOAD='(-0.01,0.01)';
      OUTPUT_LOAD='(1.0,-1.0)';
    'PT18B_PCLKC0_1':
      PIN_NUMBER='(0,0,0,C10,0,0,0)';
      BIDIRECTIONAL='TRUE';
      INPUT_LOAD='(-0.01,0.01)';
      OUTPUT_LOAD='(1.0,-1.0)';
    'PT18C':
      PIN_NUMBER='(0,0,0,F11,0,0,0)';
      BIDIRECTIONAL='TRUE';
      INPUT_LOAD='(-0.01,0.01)';
      OUTPUT_LOAD='(1.0,-1.0)';
    'PT18D':
      PIN_NUMBER='(0,0,0,G11,0,0,0)';
      BIDIRECTIONAL='TRUE';
      INPUT_LOAD='(-0.01,0.01)';
      OUTPUT_LOAD='(1.0,-1.0)';
    'PT21A':
      PIN_NUMBER='(0,0,0,B11,0,0,0)';
      BIDIRECTIONAL='TRUE';
      INPUT_LOAD='(-0.01,0.01)';
      OUTPUT_LOAD='(1.0,-1.0)';
    'PT21B':
      PIN_NUMBER='(0,0,0,A11,0,0,0)';
      BIDIRECTIONAL='TRUE';
      INPUT_LOAD='(-0.01,0.01)';
      OUTPUT_LOAD='(1.0,-1.0)';
    'PT21C':
      PIN_NUMBER='(0,0,0,B10,0,0,0)';
      BIDIRECTIONAL='TRUE';
      INPUT_LOAD='(-0.01,0.01)';
      OUTPUT_LOAD='(1.0,-1.0)';
    'PT21D':
      PIN_NUMBER='(0,0,0,A10,0,0,0)';
      BIDIRECTIONAL='TRUE';
      INPUT_LOAD='(-0.01,0.01)';
      OUTPUT_LOAD='(1.0,-1.0)';
    'PT22A':
      PIN_NUMBER='(0,0,0,A12,0,0,0)';
      BIDIRECTIONAL='TRUE';
      INPUT_LOAD='(-0.01,0.01)';
      OUTPUT_LOAD='(1.0,-1.0)';
    'PT22B':
      PIN_NUMBER='(0,0,0,B12,0,0,0)';
      BIDIRECTIONAL='TRUE';
      INPUT_LOAD='(-0.01,0.01)';
      OUTPUT_LOAD='(1.0,-1.0)';
    'PT22C_SCL_PCLKT0_0':
      PIN_NUMBER='(0,0,0,A13,0,0,0)';
      BIDIRECTIONAL='TRUE';
      INPUT_LOAD='(-0.01,0.01)';
      OUTPUT_LOAD='(1.0,-1.0)';
    'PT22D_SDA_PCLKC0_0':
      PIN_NUMBER='(0,0,0,B13,0,0,0)';
      BIDIRECTIONAL='TRUE';
      INPUT_LOAD='(-0.01,0.01)';
      OUTPUT_LOAD='(1.0,-1.0)';
    'PT25A':
      PIN_NUMBER='(0,0,0,C13,0,0,0)';
      BIDIRECTIONAL='TRUE';
      INPUT_LOAD='(-0.01,0.01)';
      OUTPUT_LOAD='(1.0,-1.0)';
    'PT25B':
      PIN_NUMBER='(0,0,0,B14,0,0,0)';
      BIDIRECTIONAL='TRUE';
      INPUT_LOAD='(-0.01,0.01)';
      OUTPUT_LOAD='(1.0,-1.0)';
    'PT25C':
      PIN_NUMBER='(0,0,0,G12,0,0,0)';
      BIDIRECTIONAL='TRUE';
      INPUT_LOAD='(-0.01,0.01)';
      OUTPUT_LOAD='(1.0,-1.0)';
    'PT25D':
      PIN_NUMBER='(0,0,0,F12,0,0,0)';
      BIDIRECTIONAL='TRUE';
      INPUT_LOAD='(-0.01,0.01)';
      OUTPUT_LOAD='(1.0,-1.0)';
    'PT26A':
      PIN_NUMBER='(0,0,0,D12,0,0,0)';
      BIDIRECTIONAL='TRUE';
      INPUT_LOAD='(-0.01,0.01)';
      OUTPUT_LOAD='(1.0,-1.0)';
    'PT26B':
      PIN_NUMBER='(0,0,0,E12,0,0,0)';
      BIDIRECTIONAL='TRUE';
      INPUT_LOAD='(-0.01,0.01)';
      OUTPUT_LOAD='(1.0,-1.0)';
    'PT26C':
      PIN_NUMBER='(0,0,0,B15,0,0,0)';
      BIDIRECTIONAL='TRUE';
      INPUT_LOAD='(-0.01,0.01)';
      OUTPUT_LOAD='(1.0,-1.0)';
    'PT26D':
      PIN_NUMBER='(0,0,0,C15,0,0,0)';
      BIDIRECTIONAL='TRUE';
      INPUT_LOAD='(-0.01,0.01)';
      OUTPUT_LOAD='(1.0,-1.0)';
    'PT27A':
      PIN_NUMBER='(0,0,0,G13,0,0,0)';
      BIDIRECTIONAL='TRUE';
      INPUT_LOAD='(-0.01,0.01)';
      OUTPUT_LOAD='(1.0,-1.0)';
    'PT27B':
      PIN_NUMBER='(0,0,0,F13,0,0,0)';
      BIDIRECTIONAL='TRUE';
      INPUT_LOAD='(-0.01,0.01)';
      OUTPUT_LOAD='(1.0,-1.0)';
    'PT27C_JTAGENB':
      PIN_NUMBER='(0,0,0,A16,0,0,0)';
      BIDIRECTIONAL='TRUE';
      INPUT_LOAD='(-0.01,0.01)';
      OUTPUT_LOAD='(1.0,-1.0)';
    'PT27D_PROGRAMN':
      PIN_NUMBER='(0,0,0,B16,0,0,0)';
      BIDIRECTIONAL='TRUE';
      INPUT_LOAD='(-0.01,0.01)';
      OUTPUT_LOAD='(1.0,-1.0)';
    'PT28A':
      PIN_NUMBER='(0,0,0,C16,0,0,0)';
      BIDIRECTIONAL='TRUE';
      INPUT_LOAD='(-0.01,0.01)';
      OUTPUT_LOAD='(1.0,-1.0)';
    'PT28B':
      PIN_NUMBER='(0,0,0,A17,0,0,0)';
      BIDIRECTIONAL='TRUE';
      INPUT_LOAD='(-0.01,0.01)';
      OUTPUT_LOAD='(1.0,-1.0)';
    'PT28C':
      PIN_NUMBER='(0,0,0,D14,0,0,0)';
      BIDIRECTIONAL='TRUE';
      INPUT_LOAD='(-0.01,0.01)';
      OUTPUT_LOAD='(1.0,-1.0)';
    'PT28D':
      PIN_NUMBER='(0,0,0,E14,0,0,0)';
      BIDIRECTIONAL='TRUE';
      INPUT_LOAD='(-0.01,0.01)';
      OUTPUT_LOAD='(1.0,-1.0)';
    'PT32A':
      PIN_NUMBER='(0,0,0,D15,0,0,0)';
      BIDIRECTIONAL='TRUE';
      INPUT_LOAD='(-0.01,0.01)';
      OUTPUT_LOAD='(1.0,-1.0)';
    'PT32B':
      PIN_NUMBER='(0,0,0,E15,0,0,0)';
      BIDIRECTIONAL='TRUE';
      INPUT_LOAD='(-0.01,0.01)';
      OUTPUT_LOAD='(1.0,-1.0)';
    'PT32C':
      PIN_NUMBER='(0,0,0,C17,0,0,0)';
      BIDIRECTIONAL='TRUE';
      INPUT_LOAD='(-0.01,0.01)';
      OUTPUT_LOAD='(1.0,-1.0)';
    'PT32D':
      PIN_NUMBER='(0,0,0,A18,0,0,0)';
      BIDIRECTIONAL='TRUE';
      INPUT_LOAD='(-0.01,0.01)';
      OUTPUT_LOAD='(1.0,-1.0)';
    'PT33A':
      PIN_NUMBER='(0,0,0,C18,0,0,0)';
      BIDIRECTIONAL='TRUE';
      INPUT_LOAD='(-0.01,0.01)';
      OUTPUT_LOAD='(1.0,-1.0)';
    'PT33B':
      PIN_NUMBER='(0,0,0,B19,0,0,0)';
      BIDIRECTIONAL='TRUE';
      INPUT_LOAD='(-0.01,0.01)';
      OUTPUT_LOAD='(1.0,-1.0)';
    'PT33C':
      PIN_NUMBER='(0,0,0,D16,0,0,0)';
      BIDIRECTIONAL='TRUE';
      INPUT_LOAD='(-0.01,0.01)';
      OUTPUT_LOAD='(1.0,-1.0)';
    'PT33D':
      PIN_NUMBER='(0,0,0,D17,0,0,0)';
      BIDIRECTIONAL='TRUE';
      INPUT_LOAD='(-0.01,0.01)';
      OUTPUT_LOAD='(1.0,-1.0)';
    'PT34A':
      PIN_NUMBER='(0,0,0,E16,0,0,0)';
      BIDIRECTIONAL='TRUE';
      INPUT_LOAD='(-0.01,0.01)';
      OUTPUT_LOAD='(1.0,-1.0)';
    'PT34B':
      PIN_NUMBER='(0,0,0,F15,0,0,0)';
      BIDIRECTIONAL='TRUE';
      INPUT_LOAD='(-0.01,0.01)';
      OUTPUT_LOAD='(1.0,-1.0)';
    'PT34C':
      PIN_NUMBER='(0,0,0,A20,0,0,0)';
      BIDIRECTIONAL='TRUE';
      INPUT_LOAD='(-0.01,0.01)';
      OUTPUT_LOAD='(1.0,-1.0)';
    'PT34D':
      PIN_NUMBER='(0,0,0,A21,0,0,0)';
      BIDIRECTIONAL='TRUE';
      INPUT_LOAD='(-0.01,0.01)';
      OUTPUT_LOAD='(1.0,-1.0)';
    'PT35A':
      PIN_NUMBER='(0,0,0,C19,0,0,0)';
      BIDIRECTIONAL='TRUE';
      INPUT_LOAD='(-0.01,0.01)';
      OUTPUT_LOAD='(1.0,-1.0)';
    'PT35B':
      PIN_NUMBER='(0,0,0,D18,0,0,0)';
      BIDIRECTIONAL='TRUE';
      INPUT_LOAD='(-0.01,0.01)';
      OUTPUT_LOAD='(1.0,-1.0)';
    'PT35C':
      PIN_NUMBER='(0,0,0,G15,0,0,0)';
      BIDIRECTIONAL='TRUE';
      INPUT_LOAD='(-0.01,0.01)';
      OUTPUT_LOAD='(1.0,-1.0)';
    'PT35D':
      PIN_NUMBER='(0,0,0,F16,0,0,0)';
      BIDIRECTIONAL='TRUE';
      INPUT_LOAD='(-0.01,0.01)';
      OUTPUT_LOAD='(1.0,-1.0)';
    'PT36A':
      PIN_NUMBER='(0,0,0,E17,0,0,0)';
      BIDIRECTIONAL='TRUE';
      INPUT_LOAD='(-0.01,0.01)';
      OUTPUT_LOAD='(1.0,-1.0)';
    'PT36B':
      PIN_NUMBER='(0,0,0,F17,0,0,0)';
      BIDIRECTIONAL='TRUE';
      INPUT_LOAD='(-0.01,0.01)';
      OUTPUT_LOAD='(1.0,-1.0)';
    'PT36C_INITN':
      PIN_NUMBER='(0,0,0,B20,0,0,0)';
      BIDIRECTIONAL='TRUE';
      INPUT_LOAD='(-0.01,0.01)';
      OUTPUT_LOAD='(1.0,-1.0)';
    'PT36D_DONE':
      PIN_NUMBER='(0,0,0,C20,0,0,0)';
      BIDIRECTIONAL='TRUE';
      INPUT_LOAD='(-0.01,0.01)';
      OUTPUT_LOAD='(1.0,-1.0)';
    'PT9A':
      PIN_NUMBER='(0,0,0,D4,0,0,0)';
      BIDIRECTIONAL='TRUE';
      INPUT_LOAD='(-0.01,0.01)';
      OUTPUT_LOAD='(1.0,-1.0)';
    'PT9B':
      PIN_NUMBER='(0,0,0,B3,0,0,0)';
      BIDIRECTIONAL='TRUE';
      INPUT_LOAD='(-0.01,0.01)';
      OUTPUT_LOAD='(1.0,-1.0)';
    'PT9C':
      PIN_NUMBER='(0,0,0,G7,0,0,0)';
      BIDIRECTIONAL='TRUE';
      INPUT_LOAD='(-0.01,0.01)';
      OUTPUT_LOAD='(1.0,-1.0)';
    'PT9D':
      PIN_NUMBER='(0,0,0,E6,0,0,0)';
      BIDIRECTIONAL='TRUE';
      INPUT_LOAD='(-0.01,0.01)';
      OUTPUT_LOAD='(1.0,-1.0)';
    'VCC'<11>:
      PIN_NUMBER='(0,0,0,0,0,K10,0)';
      PINUSE='POWER';
      NO_LOAD_CHECK='Both';
      NO_IO_CHECK='Both';
      NO_ASSERT_CHECK='TRUE';
      NO_DIR_CHECK='TRUE';
      ALLOW_CONNECT='TRUE';
    'VCC'<10>:
      PIN_NUMBER='(0,0,0,0,0,K11,0)';
      PINUSE='POWER';
      NO_LOAD_CHECK='Both';
      NO_IO_CHECK='Both';
      NO_ASSERT_CHECK='TRUE';
      NO_DIR_CHECK='TRUE';
      ALLOW_CONNECT='TRUE';
    'VCC'<9>:
      PIN_NUMBER='(0,0,0,0,0,K12,0)';
      PINUSE='POWER';
      NO_LOAD_CHECK='Both';
      NO_IO_CHECK='Both';
      NO_ASSERT_CHECK='TRUE';
      NO_DIR_CHECK='TRUE';
      ALLOW_CONNECT='TRUE';
    'VCC'<8>:
      PIN_NUMBER='(0,0,0,0,0,K13,0)';
      PINUSE='POWER';
      NO_LOAD_CHECK='Both';
      NO_IO_CHECK='Both';
      NO_ASSERT_CHECK='TRUE';
      NO_DIR_CHECK='TRUE';
      ALLOW_CONNECT='TRUE';
    'VCC'<7>:
      PIN_NUMBER='(0,0,0,0,0,L10,0)';
      PINUSE='POWER';
      NO_LOAD_CHECK='Both';
      NO_IO_CHECK='Both';
      NO_ASSERT_CHECK='TRUE';
      NO_DIR_CHECK='TRUE';
      ALLOW_CONNECT='TRUE';
    'VCC'<6>:
      PIN_NUMBER='(0,0,0,0,0,L13,0)';
      PINUSE='POWER';
      NO_LOAD_CHECK='Both';
      NO_IO_CHECK='Both';
      NO_ASSERT_CHECK='TRUE';
      NO_DIR_CHECK='TRUE';
      ALLOW_CONNECT='TRUE';
    'VCC'<5>:
      PIN_NUMBER='(0,0,0,0,0,M10,0)';
      PINUSE='POWER';
      NO_LOAD_CHECK='Both';
      NO_IO_CHECK='Both';
      NO_ASSERT_CHECK='TRUE';
      NO_DIR_CHECK='TRUE';
      ALLOW_CONNECT='TRUE';
    'VCC'<4>:
      PIN_NUMBER='(0,0,0,0,0,M13,0)';
      PINUSE='POWER';
      NO_LOAD_CHECK='Both';
      NO_IO_CHECK='Both';
      NO_ASSERT_CHECK='TRUE';
      NO_DIR_CHECK='TRUE';
      ALLOW_CONNECT='TRUE';
    'VCC'<3>:
      PIN_NUMBER='(0,0,0,0,0,N10,0)';
      PINUSE='POWER';
      NO_LOAD_CHECK='Both';
      NO_IO_CHECK='Both';
      NO_ASSERT_CHECK='TRUE';
      NO_DIR_CHECK='TRUE';
      ALLOW_CONNECT='TRUE';
    'VCC'<2>:
      PIN_NUMBER='(0,0,0,0,0,N11,0)';
      PINUSE='POWER';
      NO_LOAD_CHECK='Both';
      NO_IO_CHECK='Both';
      NO_ASSERT_CHECK='TRUE';
      NO_DIR_CHECK='TRUE';
      ALLOW_CONNECT='TRUE';
    'VCC'<1>:
      PIN_NUMBER='(0,0,0,0,0,N12,0)';
      PINUSE='POWER';
      NO_LOAD_CHECK='Both';
      NO_IO_CHECK='Both';
      NO_ASSERT_CHECK='TRUE';
      NO_DIR_CHECK='TRUE';
      ALLOW_CONNECT='TRUE';
    'VCC'<0>:
      PIN_NUMBER='(0,0,0,0,0,N13,0)';
      PINUSE='POWER';
      NO_LOAD_CHECK='Both';
      NO_IO_CHECK='Both';
      NO_ASSERT_CHECK='TRUE';
      NO_DIR_CHECK='TRUE';
      ALLOW_CONNECT='TRUE';
    'VCCIO0'<9>:
      PIN_NUMBER='(0,0,0,0,0,H14,0)';
      PINUSE='POWER';
      NO_LOAD_CHECK='Both';
      NO_IO_CHECK='Both';
      NO_ASSERT_CHECK='TRUE';
      NO_DIR_CHECK='TRUE';
      ALLOW_CONNECT='TRUE';
    'VCCIO0'<8>:
      PIN_NUMBER='(0,0,0,0,0,H13,0)';
      PINUSE='POWER';
      NO_LOAD_CHECK='Both';
      NO_IO_CHECK='Both';
      NO_ASSERT_CHECK='TRUE';
      NO_DIR_CHECK='TRUE';
      ALLOW_CONNECT='TRUE';
    'VCCIO0'<7>:
      PIN_NUMBER='(0,0,0,0,0,H12,0)';
      PINUSE='POWER';
      NO_LOAD_CHECK='Both';
      NO_IO_CHECK='Both';
      NO_ASSERT_CHECK='TRUE';
      NO_DIR_CHECK='TRUE';
      ALLOW_CONNECT='TRUE';
    'VCCIO0'<6>:
      PIN_NUMBER='(0,0,0,0,0,H11,0)';
      PINUSE='POWER';
      NO_LOAD_CHECK='Both';
      NO_IO_CHECK='Both';
      NO_ASSERT_CHECK='TRUE';
      NO_DIR_CHECK='TRUE';
      ALLOW_CONNECT='TRUE';
    'VCCIO0'<5>:
      PIN_NUMBER='(0,0,0,0,0,H10,0)';
      PINUSE='POWER';
      NO_LOAD_CHECK='Both';
      NO_IO_CHECK='Both';
      NO_ASSERT_CHECK='TRUE';
      NO_DIR_CHECK='TRUE';
      ALLOW_CONNECT='TRUE';
    'VCCIO0'<4>:
      PIN_NUMBER='(0,0,0,0,0,H9,0)';
      PINUSE='POWER';
      NO_LOAD_CHECK='Both';
      NO_IO_CHECK='Both';
      NO_ASSERT_CHECK='TRUE';
      NO_DIR_CHECK='TRUE';
      ALLOW_CONNECT='TRUE';
    'VCCIO0'<3>:
      PIN_NUMBER='(0,0,0,0,0,D13,0)';
      PINUSE='POWER';
      NO_LOAD_CHECK='Both';
      NO_IO_CHECK='Both';
      NO_ASSERT_CHECK='TRUE';
      NO_DIR_CHECK='TRUE';
      ALLOW_CONNECT='TRUE';
    'VCCIO0'<2>:
      PIN_NUMBER='(0,0,0,0,0,D10,0)';
      PINUSE='POWER';
      NO_LOAD_CHECK='Both';
      NO_IO_CHECK='Both';
      NO_ASSERT_CHECK='TRUE';
      NO_DIR_CHECK='TRUE';
      ALLOW_CONNECT='TRUE';
    'VCCIO0'<1>:
      PIN_NUMBER='(0,0,0,0,0,B17,0)';
      PINUSE='POWER';
      NO_LOAD_CHECK='Both';
      NO_IO_CHECK='Both';
      NO_ASSERT_CHECK='TRUE';
      NO_DIR_CHECK='TRUE';
      ALLOW_CONNECT='TRUE';
    'VCCIO0'<0>:
      PIN_NUMBER='(0,0,0,0,0,B6,0)';
      PINUSE='POWER';
      NO_LOAD_CHECK='Both';
      NO_IO_CHECK='Both';
      NO_ASSERT_CHECK='TRUE';
      NO_DIR_CHECK='TRUE';
      ALLOW_CONNECT='TRUE';
    'VCCIO1'<9>:
      PIN_NUMBER='(0,0,0,0,0,U21,0)';
      PINUSE='POWER';
      NO_LOAD_CHECK='Both';
      NO_IO_CHECK='Both';
      NO_ASSERT_CHECK='TRUE';
      NO_DIR_CHECK='TRUE';
      ALLOW_CONNECT='TRUE';
    'VCCIO1'<8>:
      PIN_NUMBER='(0,0,0,0,0,P15,0)';
      PINUSE='POWER';
      NO_LOAD_CHECK='Both';
      NO_IO_CHECK='Both';
      NO_ASSERT_CHECK='TRUE';
      NO_DIR_CHECK='TRUE';
      ALLOW_CONNECT='TRUE';
    'VCCIO1'<7>:
      PIN_NUMBER='(0,0,0,0,0,N19,0)';
      PINUSE='POWER';
      NO_LOAD_CHECK='Both';
      NO_IO_CHECK='Both';
      NO_ASSERT_CHECK='TRUE';
      NO_DIR_CHECK='TRUE';
      ALLOW_CONNECT='TRUE';
    'VCCIO1'<6>:
      PIN_NUMBER='(0,0,0,0,0,N15,0)';
      PINUSE='POWER';
      NO_LOAD_CHECK='Both';
      NO_IO_CHECK='Both';
      NO_ASSERT_CHECK='TRUE';
      NO_DIR_CHECK='TRUE';
      ALLOW_CONNECT='TRUE';
    'VCCIO1'<5>:
      PIN_NUMBER='(0,0,0,0,0,M15,0)';
      PINUSE='POWER';
      NO_LOAD_CHECK='Both';
      NO_IO_CHECK='Both';
      NO_ASSERT_CHECK='TRUE';
      NO_DIR_CHECK='TRUE';
      ALLOW_CONNECT='TRUE';
    'VCCIO1'<4>:
      PIN_NUMBER='(0,0,0,0,0,L15,0)';
      PINUSE='POWER';
      NO_LOAD_CHECK='Both';
      NO_IO_CHECK='Both';
      NO_ASSERT_CHECK='TRUE';
      NO_DIR_CHECK='TRUE';
      ALLOW_CONNECT='TRUE';
    'VCCIO1'<3>:
      PIN_NUMBER='(0,0,0,0,0,K19,0)';
      PINUSE='POWER';
      NO_LOAD_CHECK='Both';
      NO_IO_CHECK='Both';
      NO_ASSERT_CHECK='TRUE';
      NO_DIR_CHECK='TRUE';
      ALLOW_CONNECT='TRUE';
    'VCCIO1'<2>:
      PIN_NUMBER='(0,0,0,0,0,K15,0)';
      PINUSE='POWER';
      NO_LOAD_CHECK='Both';
      NO_IO_CHECK='Both';
      NO_ASSERT_CHECK='TRUE';
      NO_DIR_CHECK='TRUE';
      ALLOW_CONNECT='TRUE';
    'VCCIO1'<1>:
      PIN_NUMBER='(0,0,0,0,0,J15,0)';
      PINUSE='POWER';
      NO_LOAD_CHECK='Both';
      NO_IO_CHECK='Both';
      NO_ASSERT_CHECK='TRUE';
      NO_DIR_CHECK='TRUE';
      ALLOW_CONNECT='TRUE';
    'VCCIO1'<0>:
      PIN_NUMBER='(0,0,0,0,0,F21,0)';
      PINUSE='POWER';
      NO_LOAD_CHECK='Both';
      NO_IO_CHECK='Both';
      NO_ASSERT_CHECK='TRUE';
      NO_DIR_CHECK='TRUE';
      ALLOW_CONNECT='TRUE';
    'VCCIO2'<9>:
      PIN_NUMBER='(0,0,0,0,0,W13,0)';
      PINUSE='POWER';
      NO_LOAD_CHECK='Both';
      NO_IO_CHECK='Both';
      NO_ASSERT_CHECK='TRUE';
      NO_DIR_CHECK='TRUE';
      ALLOW_CONNECT='TRUE';
    'VCCIO2'<8>:
      PIN_NUMBER='(0,0,0,0,0,W10,0)';
      PINUSE='POWER';
      NO_LOAD_CHECK='Both';
      NO_IO_CHECK='Both';
      NO_ASSERT_CHECK='TRUE';
      NO_DIR_CHECK='TRUE';
      ALLOW_CONNECT='TRUE';
    'VCCIO2'<7>:
      PIN_NUMBER='(0,0,0,0,0,R14,0)';
      PINUSE='POWER';
      NO_LOAD_CHECK='Both';
      NO_IO_CHECK='Both';
      NO_ASSERT_CHECK='TRUE';
      NO_DIR_CHECK='TRUE';
      ALLOW_CONNECT='TRUE';
    'VCCIO2'<6>:
      PIN_NUMBER='(0,0,0,0,0,R13,0)';
      PINUSE='POWER';
      NO_LOAD_CHECK='Both';
      NO_IO_CHECK='Both';
      NO_ASSERT_CHECK='TRUE';
      NO_DIR_CHECK='TRUE';
      ALLOW_CONNECT='TRUE';
    'VCCIO2'<5>:
      PIN_NUMBER='(0,0,0,0,0,R12,0)';
      PINUSE='POWER';
      NO_LOAD_CHECK='Both';
      NO_IO_CHECK='Both';
      NO_ASSERT_CHECK='TRUE';
      NO_DIR_CHECK='TRUE';
      ALLOW_CONNECT='TRUE';
    'VCCIO2'<4>:
      PIN_NUMBER='(0,0,0,0,0,R11,0)';
      PINUSE='POWER';
      NO_LOAD_CHECK='Both';
      NO_IO_CHECK='Both';
      NO_ASSERT_CHECK='TRUE';
      NO_DIR_CHECK='TRUE';
      ALLOW_CONNECT='TRUE';
    'VCCIO2'<3>:
      PIN_NUMBER='(0,0,0,0,0,R10,0)';
      PINUSE='POWER';
      NO_LOAD_CHECK='Both';
      NO_IO_CHECK='Both';
      NO_ASSERT_CHECK='TRUE';
      NO_DIR_CHECK='TRUE';
      ALLOW_CONNECT='TRUE';
    'VCCIO2'<2>:
      PIN_NUMBER='(0,0,0,0,0,R9,0)';
      PINUSE='POWER';
      NO_LOAD_CHECK='Both';
      NO_IO_CHECK='Both';
      NO_ASSERT_CHECK='TRUE';
      NO_DIR_CHECK='TRUE';
      ALLOW_CONNECT='TRUE';
    'VCCIO2'<1>:
      PIN_NUMBER='(0,0,0,0,0,AA17,0)';
      PINUSE='POWER';
      NO_LOAD_CHECK='Both';
      NO_IO_CHECK='Both';
      NO_ASSERT_CHECK='TRUE';
      NO_DIR_CHECK='TRUE';
      ALLOW_CONNECT='TRUE';
    'VCCIO2'<0>:
      PIN_NUMBER='(0,0,0,0,0,AA6,0)';
      PINUSE='POWER';
      NO_LOAD_CHECK='Both';
      NO_IO_CHECK='Both';
      NO_ASSERT_CHECK='TRUE';
      NO_DIR_CHECK='TRUE';
      ALLOW_CONNECT='TRUE';
    'VCCIO3'<2>:
      PIN_NUMBER='(0,0,0,0,0,U2,0)';
      PINUSE='POWER';
      NO_LOAD_CHECK='Both';
      NO_IO_CHECK='Both';
      NO_ASSERT_CHECK='TRUE';
      NO_DIR_CHECK='TRUE';
      ALLOW_CONNECT='TRUE';
    'VCCIO3'<1>:
      PIN_NUMBER='(0,0,0,0,0,P8,0)';
      PINUSE='POWER';
      NO_LOAD_CHECK='Both';
      NO_IO_CHECK='Both';
      NO_ASSERT_CHECK='TRUE';
      NO_DIR_CHECK='TRUE';
      ALLOW_CONNECT='TRUE';
    'VCCIO3'<0>:
      PIN_NUMBER='(0,0,0,0,0,N8,0)';
      PINUSE='POWER';
      NO_LOAD_CHECK='Both';
      NO_IO_CHECK='Both';
      NO_ASSERT_CHECK='TRUE';
      NO_DIR_CHECK='TRUE';
      ALLOW_CONNECT='TRUE';
    'VCCIO4'<3>:
      PIN_NUMBER='(0,0,0,0,0,N4,0)';
      PINUSE='POWER';
      NO_LOAD_CHECK='Both';
      NO_IO_CHECK='Both';
      NO_ASSERT_CHECK='TRUE';
      NO_DIR_CHECK='TRUE';
      ALLOW_CONNECT='TRUE';
    'VCCIO4'<2>:
      PIN_NUMBER='(0,0,0,0,0,M8,0)';
      PINUSE='POWER';
      NO_LOAD_CHECK='Both';
      NO_IO_CHECK='Both';
      NO_ASSERT_CHECK='TRUE';
      NO_DIR_CHECK='TRUE';
      ALLOW_CONNECT='TRUE';
    'VCCIO4'<1>:
      PIN_NUMBER='(0,0,0,0,0,L8,0)';
      PINUSE='POWER';
      NO_LOAD_CHECK='Both';
      NO_IO_CHECK='Both';
      NO_ASSERT_CHECK='TRUE';
      NO_DIR_CHECK='TRUE';
      ALLOW_CONNECT='TRUE';
    'VCCIO4'<0>:
      PIN_NUMBER='(0,0,0,0,0,K4,0)';
      PINUSE='POWER';
      NO_LOAD_CHECK='Both';
      NO_IO_CHECK='Both';
      NO_ASSERT_CHECK='TRUE';
      NO_DIR_CHECK='TRUE';
      ALLOW_CONNECT='TRUE';
    'VCCIO5'<2>:
      PIN_NUMBER='(0,0,0,0,0,K8,0)';
      PINUSE='POWER';
      NO_LOAD_CHECK='Both';
      NO_IO_CHECK='Both';
      NO_ASSERT_CHECK='TRUE';
      NO_DIR_CHECK='TRUE';
      ALLOW_CONNECT='TRUE';
    'VCCIO5'<1>:
      PIN_NUMBER='(0,0,0,0,0,J8,0)';
      PINUSE='POWER';
      NO_LOAD_CHECK='Both';
      NO_IO_CHECK='Both';
      NO_ASSERT_CHECK='TRUE';
      NO_DIR_CHECK='TRUE';
      ALLOW_CONNECT='TRUE';
    'VCCIO5'<0>:
      PIN_NUMBER='(0,0,0,0,0,F2,0)';
      PINUSE='POWER';
      NO_LOAD_CHECK='Both';
      NO_IO_CHECK='Both';
      NO_ASSERT_CHECK='TRUE';
      NO_DIR_CHECK='TRUE';
      ALLOW_CONNECT='TRUE';
  end_pin;
  body
    PART_NAME='LCMXO2_A';
    PHYS_DES_PREFIX='U';
  end_body;
end_primitive;
primitive 'LCMXO2_A_SM1';
  pin
    'GND'<7>:
      PIN_NUMBER='(92)';
      PINUSE='GROUND';
      NO_LOAD_CHECK='Both';
      NO_IO_CHECK='Both';
      NO_ASSERT_CHECK='TRUE';
      NO_DIR_CHECK='TRUE';
      ALLOW_CONNECT='TRUE';
    'GND'<6>:
      PIN_NUMBER='(79)';
      PINUSE='GROUND';
      NO_LOAD_CHECK='Both';
      NO_IO_CHECK='Both';
      NO_ASSERT_CHECK='TRUE';
      NO_DIR_CHECK='TRUE';
      ALLOW_CONNECT='TRUE';
    'GND'<5>:
      PIN_NUMBER='(72)';
      PINUSE='GROUND';
      NO_LOAD_CHECK='Both';
      NO_IO_CHECK='Both';
      NO_ASSERT_CHECK='TRUE';
      NO_DIR_CHECK='TRUE';
      ALLOW_CONNECT='TRUE';
    'GND'<4>:
      PIN_NUMBER='(56)';
      PINUSE='GROUND';
      NO_LOAD_CHECK='Both';
      NO_IO_CHECK='Both';
      NO_ASSERT_CHECK='TRUE';
      NO_DIR_CHECK='TRUE';
      ALLOW_CONNECT='TRUE';
    'GND'<3>:
      PIN_NUMBER='(44)';
      PINUSE='GROUND';
      NO_LOAD_CHECK='Both';
      NO_IO_CHECK='Both';
      NO_ASSERT_CHECK='TRUE';
      NO_DIR_CHECK='TRUE';
      ALLOW_CONNECT='TRUE';
    'GND'<2>:
      PIN_NUMBER='(33)';
      PINUSE='GROUND';
      NO_LOAD_CHECK='Both';
      NO_IO_CHECK='Both';
      NO_ASSERT_CHECK='TRUE';
      NO_DIR_CHECK='TRUE';
      ALLOW_CONNECT='TRUE';
    'GND'<1>:
      PIN_NUMBER='(22)';
      PINUSE='GROUND';
      NO_LOAD_CHECK='Both';
      NO_IO_CHECK='Both';
      NO_ASSERT_CHECK='TRUE';
      NO_DIR_CHECK='TRUE';
      ALLOW_CONNECT='TRUE';
    'GND'<0>:
      PIN_NUMBER='(6)';
      PINUSE='GROUND';
      NO_LOAD_CHECK='Both';
      NO_IO_CHECK='Both';
      NO_ASSERT_CHECK='TRUE';
      NO_DIR_CHECK='TRUE';
      ALLOW_CONNECT='TRUE';
    'NC'<0>:
      PIN_NUMBER='(89)';
      PINUSE='NC';
      NO_LOAD_CHECK='Both';
      NO_IO_CHECK='Both';
      NO_ASSERT_CHECK='TRUE';
      NO_DIR_CHECK='TRUE';
      ALLOW_CONNECT='TRUE';
    'PB11A':
      PIN_NUMBER='(34)';
      BIDIRECTIONAL='TRUE';
      INPUT_LOAD='(-0.01,0.01)';
      OUTPUT_LOAD='(1.0,-1.0)';
    'PB11B':
      PIN_NUMBER='(35)';
      BIDIRECTIONAL='TRUE';
      INPUT_LOAD='(-0.01,0.01)';
      OUTPUT_LOAD='(1.0,-1.0)';
    'PB12A':
      PIN_NUMBER='(36)';
      BIDIRECTIONAL='TRUE';
      INPUT_LOAD='(-0.01,0.01)';
      OUTPUT_LOAD='(1.0,-1.0)';
    'PB12B':
      PIN_NUMBER='(37)';
      BIDIRECTIONAL='TRUE';
      INPUT_LOAD='(-0.01,0.01)';
      OUTPUT_LOAD='(1.0,-1.0)';
    'PB16A':
      PIN_NUMBER='(38)';
      BIDIRECTIONAL='TRUE';
      INPUT_LOAD='(-0.01,0.01)';
      OUTPUT_LOAD='(1.0,-1.0)';
    'PB16B':
      PIN_NUMBER='(39)';
      BIDIRECTIONAL='TRUE';
      INPUT_LOAD='(-0.01,0.01)';
      OUTPUT_LOAD='(1.0,-1.0)';
    'PB18A':
      PIN_NUMBER='(40)';
      BIDIRECTIONAL='TRUE';
      INPUT_LOAD='(-0.01,0.01)';
      OUTPUT_LOAD='(1.0,-1.0)';
    'PB18B':
      PIN_NUMBER='(41)';
      BIDIRECTIONAL='TRUE';
      INPUT_LOAD='(-0.01,0.01)';
      OUTPUT_LOAD='(1.0,-1.0)';
    'PB21A':
      PIN_NUMBER='(42)';
      BIDIRECTIONAL='TRUE';
      INPUT_LOAD='(-0.01,0.01)';
      OUTPUT_LOAD='(1.0,-1.0)';
    'PB21B':
      PIN_NUMBER='(43)';
      BIDIRECTIONAL='TRUE';
      INPUT_LOAD='(-0.01,0.01)';
      OUTPUT_LOAD='(1.0,-1.0)';
    'PB22A':
      PIN_NUMBER='(45)';
      BIDIRECTIONAL='TRUE';
      INPUT_LOAD='(-0.01,0.01)';
      OUTPUT_LOAD='(1.0,-1.0)';
    'PB22B':
      PIN_NUMBER='(47)';
      BIDIRECTIONAL='TRUE';
      INPUT_LOAD='(-0.01,0.01)';
      OUTPUT_LOAD='(1.0,-1.0)';
    'PB25A':
      PIN_NUMBER='(48)';
      BIDIRECTIONAL='TRUE';
      INPUT_LOAD='(-0.01,0.01)';
      OUTPUT_LOAD='(1.0,-1.0)';
    'PB25B':
      PIN_NUMBER='(49)';
      BIDIRECTIONAL='TRUE';
      INPUT_LOAD='(-0.01,0.01)';
      OUTPUT_LOAD='(1.0,-1.0)';
    'PB5A':
      PIN_NUMBER='(27)';
      BIDIRECTIONAL='TRUE';
      INPUT_LOAD='(-0.01,0.01)';
      OUTPUT_LOAD='(1.0,-1.0)';
    'PB5B':
      PIN_NUMBER='(28)';
      BIDIRECTIONAL='TRUE';
      INPUT_LOAD='(-0.01,0.01)';
      OUTPUT_LOAD='(1.0,-1.0)';
    'PB6A':
      PIN_NUMBER='(29)';
      BIDIRECTIONAL='TRUE';
      INPUT_LOAD='(-0.01,0.01)';
      OUTPUT_LOAD='(1.0,-1.0)';
    'PB6B':
      PIN_NUMBER='(30)';
      BIDIRECTIONAL='TRUE';
      INPUT_LOAD='(-0.01,0.01)';
      OUTPUT_LOAD='(1.0,-1.0)';
    'PB8A':
      PIN_NUMBER='(31)';
      BIDIRECTIONAL='TRUE';
      INPUT_LOAD='(-0.01,0.01)';
      OUTPUT_LOAD='(1.0,-1.0)';
    'PB8B':
      PIN_NUMBER='(32)';
      BIDIRECTIONAL='TRUE';
      INPUT_LOAD='(-0.01,0.01)';
      OUTPUT_LOAD='(1.0,-1.0)';
    'PL10A':
      PIN_NUMBER='(16)';
      BIDIRECTIONAL='TRUE';
      INPUT_LOAD='(-0.01,0.01)';
      OUTPUT_LOAD='(1.0,-1.0)';
    'PL10B':
      PIN_NUMBER='(17)';
      BIDIRECTIONAL='TRUE';
      INPUT_LOAD='(-0.01,0.01)';
      OUTPUT_LOAD='(1.0,-1.0)';
    'PL11A':
      PIN_NUMBER='(18)';
      BIDIRECTIONAL='TRUE';
      INPUT_LOAD='(-0.01,0.01)';
      OUTPUT_LOAD='(1.0,-1.0)';
    'PL11B':
      PIN_NUMBER='(19)';
      BIDIRECTIONAL='TRUE';
      INPUT_LOAD='(-0.01,0.01)';
      OUTPUT_LOAD='(1.0,-1.0)';
    'PL12A':
      PIN_NUMBER='(20)';
      BIDIRECTIONAL='TRUE';
      INPUT_LOAD='(-0.01,0.01)';
      OUTPUT_LOAD='(1.0,-1.0)';
    'PL12B':
      PIN_NUMBER='(21)';
      BIDIRECTIONAL='TRUE';
      INPUT_LOAD='(-0.01,0.01)';
      OUTPUT_LOAD='(1.0,-1.0)';
    'PL14A':
      PIN_NUMBER='(24)';
      BIDIRECTIONAL='TRUE';
      INPUT_LOAD='(-0.01,0.01)';
      OUTPUT_LOAD='(1.0,-1.0)';
    'PL14B':
      PIN_NUMBER='(25)';
      BIDIRECTIONAL='TRUE';
      INPUT_LOAD='(-0.01,0.01)';
      OUTPUT_LOAD='(1.0,-1.0)';
    'PL2A':
      PIN_NUMBER='(1)';
      BIDIRECTIONAL='TRUE';
      INPUT_LOAD='(-0.01,0.01)';
      OUTPUT_LOAD='(1.0,-1.0)';
    'PL2B':
      PIN_NUMBER='(2)';
      BIDIRECTIONAL='TRUE';
      INPUT_LOAD='(-0.01,0.01)';
      OUTPUT_LOAD='(1.0,-1.0)';
    'PL3A':
      PIN_NUMBER='(3)';
      BIDIRECTIONAL='TRUE';
      INPUT_LOAD='(-0.01,0.01)';
      OUTPUT_LOAD='(1.0,-1.0)';
    'PL3B':
      PIN_NUMBER='(4)';
      BIDIRECTIONAL='TRUE';
      INPUT_LOAD='(-0.01,0.01)';
      OUTPUT_LOAD='(1.0,-1.0)';
    'PL4A':
      PIN_NUMBER='(7)';
      BIDIRECTIONAL='TRUE';
      INPUT_LOAD='(-0.01,0.01)';
      OUTPUT_LOAD='(1.0,-1.0)';
    'PL4B':
      PIN_NUMBER='(8)';
      BIDIRECTIONAL='TRUE';
      INPUT_LOAD='(-0.01,0.01)';
      OUTPUT_LOAD='(1.0,-1.0)';
    'PL5A':
      PIN_NUMBER='(9)';
      BIDIRECTIONAL='TRUE';
      INPUT_LOAD='(-0.01,0.01)';
      OUTPUT_LOAD='(1.0,-1.0)';
    'PL5B':
      PIN_NUMBER='(10)';
      BIDIRECTIONAL='TRUE';
      INPUT_LOAD='(-0.01,0.01)';
      OUTPUT_LOAD='(1.0,-1.0)';
    'PL7C':
      PIN_NUMBER='(12)';
      BIDIRECTIONAL='TRUE';
      INPUT_LOAD='(-0.01,0.01)';
      OUTPUT_LOAD='(1.0,-1.0)';
    'PL7D':
      PIN_NUMBER='(13)';
      BIDIRECTIONAL='TRUE';
      INPUT_LOAD='(-0.01,0.01)';
      OUTPUT_LOAD='(1.0,-1.0)';
    'PL9A':
      PIN_NUMBER='(14)';
      BIDIRECTIONAL='TRUE';
      INPUT_LOAD='(-0.01,0.01)';
      OUTPUT_LOAD='(1.0,-1.0)';
    'PL9B':
      PIN_NUMBER='(15)';
      BIDIRECTIONAL='TRUE';
      INPUT_LOAD='(-0.01,0.01)';
      OUTPUT_LOAD='(1.0,-1.0)';
    'PR10A':
      PIN_NUMBER='(60)';
      BIDIRECTIONAL='TRUE';
      INPUT_LOAD='(-0.01,0.01)';
      OUTPUT_LOAD='(1.0,-1.0)';
    'PR10B':
      PIN_NUMBER='(59)';
      BIDIRECTIONAL='TRUE';
      INPUT_LOAD='(-0.01,0.01)';
      OUTPUT_LOAD='(1.0,-1.0)';
    'PR11A':
      PIN_NUMBER='(58)';
      BIDIRECTIONAL='TRUE';
      INPUT_LOAD='(-0.01,0.01)';
      OUTPUT_LOAD='(1.0,-1.0)';
    'PR11B':
      PIN_NUMBER='(57)';
      BIDIRECTIONAL='TRUE';
      INPUT_LOAD='(-0.01,0.01)';
      OUTPUT_LOAD='(1.0,-1.0)';
    'PR12A':
      PIN_NUMBER='(54)';
      BIDIRECTIONAL='TRUE';
      INPUT_LOAD='(-0.01,0.01)';
      OUTPUT_LOAD='(1.0,-1.0)';
    'PR12B':
      PIN_NUMBER='(53)';
      BIDIRECTIONAL='TRUE';
      INPUT_LOAD='(-0.01,0.01)';
      OUTPUT_LOAD='(1.0,-1.0)';
    'PR14A':
      PIN_NUMBER='(52)';
      BIDIRECTIONAL='TRUE';
      INPUT_LOAD='(-0.01,0.01)';
      OUTPUT_LOAD='(1.0,-1.0)';
    'PR14B':
      PIN_NUMBER='(51)';
      BIDIRECTIONAL='TRUE';
      INPUT_LOAD='(-0.01,0.01)';
      OUTPUT_LOAD='(1.0,-1.0)';
    'PR1A':
      PIN_NUMBER='(75)';
      BIDIRECTIONAL='TRUE';
      INPUT_LOAD='(-0.01,0.01)';
      OUTPUT_LOAD='(1.0,-1.0)';
    'PR1B':
      PIN_NUMBER='(74)';
      BIDIRECTIONAL='TRUE';
      INPUT_LOAD='(-0.01,0.01)';
      OUTPUT_LOAD='(1.0,-1.0)';
    'PR3A':
      PIN_NUMBER='(71)';
      BIDIRECTIONAL='TRUE';
      INPUT_LOAD='(-0.01,0.01)';
      OUTPUT_LOAD='(1.0,-1.0)';
    'PR3B':
      PIN_NUMBER='(70)';
      BIDIRECTIONAL='TRUE';
      INPUT_LOAD='(-0.01,0.01)';
      OUTPUT_LOAD='(1.0,-1.0)';
    'PR4A':
      PIN_NUMBER='(69)';
      BIDIRECTIONAL='TRUE';
      INPUT_LOAD='(-0.01,0.01)';
      OUTPUT_LOAD='(1.0,-1.0)';
    'PR4B':
      PIN_NUMBER='(68)';
      BIDIRECTIONAL='TRUE';
      INPUT_LOAD='(-0.01,0.01)';
      OUTPUT_LOAD='(1.0,-1.0)';
    'PR5A':
      PIN_NUMBER='(67)';
      BIDIRECTIONAL='TRUE';
      INPUT_LOAD='(-0.01,0.01)';
      OUTPUT_LOAD='(1.0,-1.0)';
    'PR5B':
      PIN_NUMBER='(66)';
      BIDIRECTIONAL='TRUE';
      INPUT_LOAD='(-0.01,0.01)';
      OUTPUT_LOAD='(1.0,-1.0)';
    'PR6A':
      PIN_NUMBER='(65)';
      BIDIRECTIONAL='TRUE';
      INPUT_LOAD='(-0.01,0.01)';
      OUTPUT_LOAD='(1.0,-1.0)';
    'PR6B':
      PIN_NUMBER='(64)';
      BIDIRECTIONAL='TRUE';
      INPUT_LOAD='(-0.01,0.01)';
      OUTPUT_LOAD='(1.0,-1.0)';
    'PR7A':
      PIN_NUMBER='(63)';
      BIDIRECTIONAL='TRUE';
      INPUT_LOAD='(-0.01,0.01)';
      OUTPUT_LOAD='(1.0,-1.0)';
    'PR7B':
      PIN_NUMBER='(62)';
      BIDIRECTIONAL='TRUE';
      INPUT_LOAD='(-0.01,0.01)';
      OUTPUT_LOAD='(1.0,-1.0)';
    'PR9A':
      PIN_NUMBER='(61)';
      BIDIRECTIONAL='TRUE';
      INPUT_LOAD='(-0.01,0.01)';
      OUTPUT_LOAD='(1.0,-1.0)';
    'PT11A':
      PIN_NUMBER='(97)';
      BIDIRECTIONAL='TRUE';
      INPUT_LOAD='(-0.01,0.01)';
      OUTPUT_LOAD='(1.0,-1.0)';
    'PT11B':
      PIN_NUMBER='(96)';
      BIDIRECTIONAL='TRUE';
      INPUT_LOAD='(-0.01,0.01)';
      OUTPUT_LOAD='(1.0,-1.0)';
    'PT12C':
      PIN_NUMBER='(95)';
      BIDIRECTIONAL='TRUE';
      INPUT_LOAD='(-0.01,0.01)';
      OUTPUT_LOAD='(1.0,-1.0)';
    'PT12D':
      PIN_NUMBER='(94)';
      BIDIRECTIONAL='TRUE';
      INPUT_LOAD='(-0.01,0.01)';
      OUTPUT_LOAD='(1.0,-1.0)';
    'PT16C':
      PIN_NUMBER='(91)';
      BIDIRECTIONAL='TRUE';
      INPUT_LOAD='(-0.01,0.01)';
      OUTPUT_LOAD='(1.0,-1.0)';
    'PT16D':
      PIN_NUMBER='(90)';
      BIDIRECTIONAL='TRUE';
      INPUT_LOAD='(-0.01,0.01)';
      OUTPUT_LOAD='(1.0,-1.0)';
    'PT17A':
      PIN_NUMBER='(88)';
      BIDIRECTIONAL='TRUE';
      INPUT_LOAD='(-0.01,0.01)';
      OUTPUT_LOAD='(1.0,-1.0)';
    'PT17B':
      PIN_NUMBER='(87)';
      BIDIRECTIONAL='TRUE';
      INPUT_LOAD='(-0.01,0.01)';
      OUTPUT_LOAD='(1.0,-1.0)';
    'PT18C':
      PIN_NUMBER='(86)';
      BIDIRECTIONAL='TRUE';
      INPUT_LOAD='(-0.01,0.01)';
      OUTPUT_LOAD='(1.0,-1.0)';
    'PT18D':
      PIN_NUMBER='(85)';
      BIDIRECTIONAL='TRUE';
      INPUT_LOAD='(-0.01,0.01)';
      OUTPUT_LOAD='(1.0,-1.0)';
    'PT19A':
      PIN_NUMBER='(84)';
      BIDIRECTIONAL='TRUE';
      INPUT_LOAD='(-0.01,0.01)';
      OUTPUT_LOAD='(1.0,-1.0)';
    'PT19B':
      PIN_NUMBER='(83)';
      BIDIRECTIONAL='TRUE';
      INPUT_LOAD='(-0.01,0.01)';
      OUTPUT_LOAD='(1.0,-1.0)';
    'PT20C':
      PIN_NUMBER='(82)';
      BIDIRECTIONAL='TRUE';
      INPUT_LOAD='(-0.01,0.01)';
      OUTPUT_LOAD='(1.0,-1.0)';
    'PT20D':
      PIN_NUMBER='(81)';
      BIDIRECTIONAL='TRUE';
      INPUT_LOAD='(-0.01,0.01)';
      OUTPUT_LOAD='(1.0,-1.0)';
    'PT22A':
      PIN_NUMBER='(78)';
      BIDIRECTIONAL='TRUE';
      INPUT_LOAD='(-0.01,0.01)';
      OUTPUT_LOAD='(1.0,-1.0)';
    'PT24C':
      PIN_NUMBER='(77)';
      BIDIRECTIONAL='TRUE';
      INPUT_LOAD='(-0.01,0.01)';
      OUTPUT_LOAD='(1.0,-1.0)';
    'PT24D':
      PIN_NUMBER='(76)';
      BIDIRECTIONAL='TRUE';
      INPUT_LOAD='(-0.01,0.01)';
      OUTPUT_LOAD='(1.0,-1.0)';
    'PT9A':
      PIN_NUMBER='(99)';
      BIDIRECTIONAL='TRUE';
      INPUT_LOAD='(-0.01,0.01)';
      OUTPUT_LOAD='(1.0,-1.0)';
    'PT9B':
      PIN_NUMBER='(98)';
      BIDIRECTIONAL='TRUE';
      INPUT_LOAD='(-0.01,0.01)';
      OUTPUT_LOAD='(1.0,-1.0)';
    'VCC'<1>:
      PIN_NUMBER='(100)';
      PINUSE='POWER';
      NO_LOAD_CHECK='Both';
      NO_IO_CHECK='Both';
      NO_ASSERT_CHECK='TRUE';
      NO_DIR_CHECK='TRUE';
      ALLOW_CONNECT='TRUE';
    'VCC'<0>:
      PIN_NUMBER='(50)';
      PINUSE='POWER';
      NO_LOAD_CHECK='Both';
      NO_IO_CHECK='Both';
      NO_ASSERT_CHECK='TRUE';
      NO_DIR_CHECK='TRUE';
      ALLOW_CONNECT='TRUE';
    'VCCIO0'<1>:
      PIN_NUMBER='(93)';
      PINUSE='POWER';
      NO_LOAD_CHECK='Both';
      NO_IO_CHECK='Both';
      NO_ASSERT_CHECK='TRUE';
      NO_DIR_CHECK='TRUE';
      ALLOW_CONNECT='TRUE';
    'VCCIO0'<0>:
      PIN_NUMBER='(80)';
      PINUSE='POWER';
      NO_LOAD_CHECK='Both';
      NO_IO_CHECK='Both';
      NO_ASSERT_CHECK='TRUE';
      NO_DIR_CHECK='TRUE';
      ALLOW_CONNECT='TRUE';
    'VCCIO1'<1>:
      PIN_NUMBER='(73)';
      PINUSE='POWER';
      NO_LOAD_CHECK='Both';
      NO_IO_CHECK='Both';
      NO_ASSERT_CHECK='TRUE';
      NO_DIR_CHECK='TRUE';
      ALLOW_CONNECT='TRUE';
    'VCCIO1'<0>:
      PIN_NUMBER='(55)';
      PINUSE='POWER';
      NO_LOAD_CHECK='Both';
      NO_IO_CHECK='Both';
      NO_ASSERT_CHECK='TRUE';
      NO_DIR_CHECK='TRUE';
      ALLOW_CONNECT='TRUE';
    'VCCIO2'<1>:
      PIN_NUMBER='(46)';
      PINUSE='POWER';
      NO_LOAD_CHECK='Both';
      NO_IO_CHECK='Both';
      NO_ASSERT_CHECK='TRUE';
      NO_DIR_CHECK='TRUE';
      ALLOW_CONNECT='TRUE';
    'VCCIO2'<0>:
      PIN_NUMBER='(26)';
      PINUSE='POWER';
      NO_LOAD_CHECK='Both';
      NO_IO_CHECK='Both';
      NO_ASSERT_CHECK='TRUE';
      NO_DIR_CHECK='TRUE';
      ALLOW_CONNECT='TRUE';
    'VCCIO3'<0>:
      PIN_NUMBER='(23)';
      PINUSE='POWER';
      NO_LOAD_CHECK='Both';
      NO_IO_CHECK='Both';
      NO_ASSERT_CHECK='TRUE';
      NO_DIR_CHECK='TRUE';
      ALLOW_CONNECT='TRUE';
    'VCCIO4'<0>:
      PIN_NUMBER='(11)';
      PINUSE='POWER';
      NO_LOAD_CHECK='Both';
      NO_IO_CHECK='Both';
      NO_ASSERT_CHECK='TRUE';
      NO_DIR_CHECK='TRUE';
      ALLOW_CONNECT='TRUE';
    'VCCIO5'<0>:
      PIN_NUMBER='(5)';
      PINUSE='POWER';
      NO_LOAD_CHECK='Both';
      NO_IO_CHECK='Both';
      NO_ASSERT_CHECK='TRUE';
      NO_DIR_CHECK='TRUE';
      ALLOW_CONNECT='TRUE';
  end_pin;
  body
    PART_NAME='LCMXO2_A';
    PHYS_DES_PREFIX='U';
  end_body;
end_primitive;
primitive 'LCMXO2_A_256BGA2';
  pin
    'GND'<23>:
      PIN_NUMBER='(0,0,R15)';
      PINUSE='GROUND';
      NO_LOAD_CHECK='Both';
      NO_IO_CHECK='Both';
      NO_ASSERT_CHECK='TRUE';
      NO_DIR_CHECK='TRUE';
      ALLOW_CONNECT='TRUE';
    'GND'<22>:
      PIN_NUMBER='(0,0,R2)';
      PINUSE='GROUND';
      NO_LOAD_CHECK='Both';
      NO_IO_CHECK='Both';
      NO_ASSERT_CHECK='TRUE';
      NO_DIR_CHECK='TRUE';
      ALLOW_CONNECT='TRUE';
    'GND'<21>:
      PIN_NUMBER='(0,0,P14)';
      PINUSE='GROUND';
      NO_LOAD_CHECK='Both';
      NO_IO_CHECK='Both';
      NO_ASSERT_CHECK='TRUE';
      NO_DIR_CHECK='TRUE';
      ALLOW_CONNECT='TRUE';
    'GND'<20>:
      PIN_NUMBER='(0,0,P3)';
      PINUSE='GROUND';
      NO_LOAD_CHECK='Both';
      NO_IO_CHECK='Both';
      NO_ASSERT_CHECK='TRUE';
      NO_DIR_CHECK='TRUE';
      ALLOW_CONNECT='TRUE';
    'GND'<19>:
      PIN_NUMBER='(0,0,N13)';
      PINUSE='GROUND';
      NO_LOAD_CHECK='Both';
      NO_IO_CHECK='Both';
      NO_ASSERT_CHECK='TRUE';
      NO_DIR_CHECK='TRUE';
      ALLOW_CONNECT='TRUE';
    'GND'<18>:
      PIN_NUMBER='(0,0,N4)';
      PINUSE='GROUND';
      NO_LOAD_CHECK='Both';
      NO_IO_CHECK='Both';
      NO_ASSERT_CHECK='TRUE';
      NO_DIR_CHECK='TRUE';
      ALLOW_CONNECT='TRUE';
    'GND'<17>:
      PIN_NUMBER='(0,0,M12)';
      PINUSE='GROUND';
      NO_LOAD_CHECK='Both';
      NO_IO_CHECK='Both';
      NO_ASSERT_CHECK='TRUE';
      NO_DIR_CHECK='TRUE';
      ALLOW_CONNECT='TRUE';
    'GND'<16>:
      PIN_NUMBER='(0,0,M5)';
      PINUSE='GROUND';
      NO_LOAD_CHECK='Both';
      NO_IO_CHECK='Both';
      NO_ASSERT_CHECK='TRUE';
      NO_DIR_CHECK='TRUE';
      ALLOW_CONNECT='TRUE';
    'GND'<15>:
      PIN_NUMBER='(0,0,L11)';
      PINUSE='GROUND';
      NO_LOAD_CHECK='Both';
      NO_IO_CHECK='Both';
      NO_ASSERT_CHECK='TRUE';
      NO_DIR_CHECK='TRUE';
      ALLOW_CONNECT='TRUE';
    'GND'<14>:
      PIN_NUMBER='(0,0,L6)';
      PINUSE='GROUND';
      NO_LOAD_CHECK='Both';
      NO_IO_CHECK='Both';
      NO_ASSERT_CHECK='TRUE';
      NO_DIR_CHECK='TRUE';
      ALLOW_CONNECT='TRUE';
    'GND'<13>:
      PIN_NUMBER='(0,0,J9)';
      PINUSE='GROUND';
      NO_LOAD_CHECK='Both';
      NO_IO_CHECK='Both';
      NO_ASSERT_CHECK='TRUE';
      NO_DIR_CHECK='TRUE';
      ALLOW_CONNECT='TRUE';
    'GND'<12>:
      PIN_NUMBER='(0,0,J8)';
      PINUSE='GROUND';
      NO_LOAD_CHECK='Both';
      NO_IO_CHECK='Both';
      NO_ASSERT_CHECK='TRUE';
      NO_DIR_CHECK='TRUE';
      ALLOW_CONNECT='TRUE';
    'GND'<11>:
      PIN_NUMBER='(0,0,H9)';
      PINUSE='GROUND';
      NO_LOAD_CHECK='Both';
      NO_IO_CHECK='Both';
      NO_ASSERT_CHECK='TRUE';
      NO_DIR_CHECK='TRUE';
      ALLOW_CONNECT='TRUE';
    'GND'<10>:
      PIN_NUMBER='(0,0,H8)';
      PINUSE='GROUND';
      NO_LOAD_CHECK='Both';
      NO_IO_CHECK='Both';
      NO_ASSERT_CHECK='TRUE';
      NO_DIR_CHECK='TRUE';
      ALLOW_CONNECT='TRUE';
    'GND'<9>:
      PIN_NUMBER='(0,0,F11)';
      PINUSE='GROUND';
      NO_LOAD_CHECK='Both';
      NO_IO_CHECK='Both';
      NO_ASSERT_CHECK='TRUE';
      NO_DIR_CHECK='TRUE';
      ALLOW_CONNECT='TRUE';
    'GND'<8>:
      PIN_NUMBER='(0,0,F6)';
      PINUSE='GROUND';
      NO_LOAD_CHECK='Both';
      NO_IO_CHECK='Both';
      NO_ASSERT_CHECK='TRUE';
      NO_DIR_CHECK='TRUE';
      ALLOW_CONNECT='TRUE';
    'GND'<7>:
      PIN_NUMBER='(0,0,E12)';
      PINUSE='GROUND';
      NO_LOAD_CHECK='Both';
      NO_IO_CHECK='Both';
      NO_ASSERT_CHECK='TRUE';
      NO_DIR_CHECK='TRUE';
      ALLOW_CONNECT='TRUE';
    'GND'<6>:
      PIN_NUMBER='(0,0,E5)';
      PINUSE='GROUND';
      NO_LOAD_CHECK='Both';
      NO_IO_CHECK='Both';
      NO_ASSERT_CHECK='TRUE';
      NO_DIR_CHECK='TRUE';
      ALLOW_CONNECT='TRUE';
    'GND'<5>:
      PIN_NUMBER='(0,0,D13)';
      PINUSE='GROUND';
      NO_LOAD_CHECK='Both';
      NO_IO_CHECK='Both';
      NO_ASSERT_CHECK='TRUE';
      NO_DIR_CHECK='TRUE';
      ALLOW_CONNECT='TRUE';
    'GND'<4>:
      PIN_NUMBER='(0,0,D4)';
      PINUSE='GROUND';
      NO_LOAD_CHECK='Both';
      NO_IO_CHECK='Both';
      NO_ASSERT_CHECK='TRUE';
      NO_DIR_CHECK='TRUE';
      ALLOW_CONNECT='TRUE';
    'GND'<3>:
      PIN_NUMBER='(0,0,C14)';
      PINUSE='GROUND';
      NO_LOAD_CHECK='Both';
      NO_IO_CHECK='Both';
      NO_ASSERT_CHECK='TRUE';
      NO_DIR_CHECK='TRUE';
      ALLOW_CONNECT='TRUE';
    'GND'<2>:
      PIN_NUMBER='(0,0,C3)';
      PINUSE='GROUND';
      NO_LOAD_CHECK='Both';
      NO_IO_CHECK='Both';
      NO_ASSERT_CHECK='TRUE';
      NO_DIR_CHECK='TRUE';
      ALLOW_CONNECT='TRUE';
    'GND'<1>:
      PIN_NUMBER='(0,0,B15)';
      PINUSE='GROUND';
      NO_LOAD_CHECK='Both';
      NO_IO_CHECK='Both';
      NO_ASSERT_CHECK='TRUE';
      NO_DIR_CHECK='TRUE';
      ALLOW_CONNECT='TRUE';
    'GND'<0>:
      PIN_NUMBER='(0,0,B2)';
      PINUSE='GROUND';
      NO_LOAD_CHECK='Both';
      NO_IO_CHECK='Both';
      NO_ASSERT_CHECK='TRUE';
      NO_DIR_CHECK='TRUE';
      ALLOW_CONNECT='TRUE';
    'NC<0>':
      PIN_NUMBER='(0,0,A2)';
      PINUSE='NC';
      NO_LOAD_CHECK='Both';
      NO_IO_CHECK='Both';
      NO_ASSERT_CHECK='TRUE';
      NO_DIR_CHECK='TRUE';
      ALLOW_CONNECT='TRUE';
    'PB10A':
      PIN_NUMBER='(N6,0,0)';
      BIDIRECTIONAL='TRUE';
      INPUT_LOAD='(-0.01,0.01)';
      OUTPUT_LOAD='(1.0,-1.0)';
    'PB10B':
      PIN_NUMBER='(L7,0,0)';
      BIDIRECTIONAL='TRUE';
      INPUT_LOAD='(-0.01,0.01)';
      OUTPUT_LOAD='(1.0,-1.0)';
    'PB12A_MCLK_CCLK':
      PIN_NUMBER='(P6,0,0)';
      BIDIRECTIONAL='TRUE';
      INPUT_LOAD='(-0.01,0.01)';
      OUTPUT_LOAD='(1.0,-1.0)';
    'PB12B_SO_SPISO':
      PIN_NUMBER='(T6,0,0)';
      BIDIRECTIONAL='TRUE';
      INPUT_LOAD='(-0.01,0.01)';
      OUTPUT_LOAD='(1.0,-1.0)';
    'PB13A':
      PIN_NUMBER='(R7,0,0)';
      BIDIRECTIONAL='TRUE';
      INPUT_LOAD='(-0.01,0.01)';
      OUTPUT_LOAD='(1.0,-1.0)';
    'PB13B':
      PIN_NUMBER='(P7,0,0)';
      BIDIRECTIONAL='TRUE';
      INPUT_LOAD='(-0.01,0.01)';
      OUTPUT_LOAD='(1.0,-1.0)';
    'PB13C':
      PIN_NUMBER='(M7,0,0)';
      BIDIRECTIONAL='TRUE';
      INPUT_LOAD='(-0.01,0.01)';
      OUTPUT_LOAD='(1.0,-1.0)';
    'PB13D':
      PIN_NUMBER='(N7,0,0)';
      BIDIRECTIONAL='TRUE';
      INPUT_LOAD='(-0.01,0.01)';
      OUTPUT_LOAD='(1.0,-1.0)';
    'PB15A':
      PIN_NUMBER='(M6,0,0)';
      BIDIRECTIONAL='TRUE';
      INPUT_LOAD='(-0.01,0.01)';
      OUTPUT_LOAD='(1.0,-1.0)';
    'PB15B':
      PIN_NUMBER='(L8,0,0)';
      BIDIRECTIONAL='TRUE';
      INPUT_LOAD='(-0.01,0.01)';
      OUTPUT_LOAD='(1.0,-1.0)';
    'PB16A_PCLKT2_0':
      PIN_NUMBER='(T7,0,0)';
      BIDIRECTIONAL='TRUE';
      INPUT_LOAD='(-0.01,0.01)';
      OUTPUT_LOAD='(1.0,-1.0)';
    'PB16B_PCLKC2_0':
      PIN_NUMBER='(R8,0,0)';
      BIDIRECTIONAL='TRUE';
      INPUT_LOAD='(-0.01,0.01)';
      OUTPUT_LOAD='(1.0,-1.0)';
    'PB18A':
      PIN_NUMBER='(P8,0,0)';
      BIDIRECTIONAL='TRUE';
      INPUT_LOAD='(-0.01,0.01)';
      OUTPUT_LOAD='(1.0,-1.0)';
    'PB18B':
      PIN_NUMBER='(T8,0,0)';
      BIDIRECTIONAL='TRUE';
      INPUT_LOAD='(-0.01,0.01)';
      OUTPUT_LOAD='(1.0,-1.0)';
    'PB18C':
      PIN_NUMBER='(N8,0,0)';
      BIDIRECTIONAL='TRUE';
      INPUT_LOAD='(-0.01,0.01)';
      OUTPUT_LOAD='(1.0,-1.0)';
    'PB18D':
      PIN_NUMBER='(L9,0,0)';
      BIDIRECTIONAL='TRUE';
      INPUT_LOAD='(-0.01,0.01)';
      OUTPUT_LOAD='(1.0,-1.0)';
    'PB21A':
      PIN_NUMBER='(M8,0,0)';
      BIDIRECTIONAL='TRUE';
      INPUT_LOAD='(-0.01,0.01)';
      OUTPUT_LOAD='(1.0,-1.0)';
    'PB21B':
      PIN_NUMBER='(N9,0,0)';
      BIDIRECTIONAL='TRUE';
      INPUT_LOAD='(-0.01,0.01)';
      OUTPUT_LOAD='(1.0,-1.0)';
    'PB23A_PCLKT2_1':
      PIN_NUMBER='(T9,0,0)';
      BIDIRECTIONAL='TRUE';
      INPUT_LOAD='(-0.01,0.01)';
      OUTPUT_LOAD='(1.0,-1.0)';
    'PB23B_PCLKC2_1':
      PIN_NUMBER='(P9,0,0)';
      BIDIRECTIONAL='TRUE';
      INPUT_LOAD='(-0.01,0.01)';
      OUTPUT_LOAD='(1.0,-1.0)';
    'PB26A':
      PIN_NUMBER='(R9,0,0)';
      BIDIRECTIONAL='TRUE';
      INPUT_LOAD='(-0.01,0.01)';
      OUTPUT_LOAD='(1.0,-1.0)';
    'PB26B':
      PIN_NUMBER='(T10,0,0)';
      BIDIRECTIONAL='TRUE';
      INPUT_LOAD='(-0.01,0.01)';
      OUTPUT_LOAD='(1.0,-1.0)';
    'PB26C':
      PIN_NUMBER='(M9,0,0)';
      BIDIRECTIONAL='TRUE';
      INPUT_LOAD='(-0.01,0.01)';
      OUTPUT_LOAD='(1.0,-1.0)';
    'PB26D':
      PIN_NUMBER='(L10,0,0)';
      BIDIRECTIONAL='TRUE';
      INPUT_LOAD='(-0.01,0.01)';
      OUTPUT_LOAD='(1.0,-1.0)';
    'PB28A':
      PIN_NUMBER='(N10,0,0)';
      BIDIRECTIONAL='TRUE';
      INPUT_LOAD='(-0.01,0.01)';
      OUTPUT_LOAD='(1.0,-1.0)';
    'PB28B':
      PIN_NUMBER='(M11,0,0)';
      BIDIRECTIONAL='TRUE';
      INPUT_LOAD='(-0.01,0.01)';
      OUTPUT_LOAD='(1.0,-1.0)';
    'PB29A':
      PIN_NUMBER='(P10,0,0)';
      BIDIRECTIONAL='TRUE';
      INPUT_LOAD='(-0.01,0.01)';
      OUTPUT_LOAD='(1.0,-1.0)';
    'PB29B':
      PIN_NUMBER='(R10,0,0)';
      BIDIRECTIONAL='TRUE';
      INPUT_LOAD='(-0.01,0.01)';
      OUTPUT_LOAD='(1.0,-1.0)';
    'PB31A':
      PIN_NUMBER='(T11,0,0)';
      BIDIRECTIONAL='TRUE';
      INPUT_LOAD='(-0.01,0.01)';
      OUTPUT_LOAD='(1.0,-1.0)';
    'PB31B':
      PIN_NUMBER='(P11,0,0)';
      BIDIRECTIONAL='TRUE';
      INPUT_LOAD='(-0.01,0.01)';
      OUTPUT_LOAD='(1.0,-1.0)';
    'PB31C':
      PIN_NUMBER='(M10,0,0)';
      BIDIRECTIONAL='TRUE';
      INPUT_LOAD='(-0.01,0.01)';
      OUTPUT_LOAD='(1.0,-1.0)';
    'PB31D':
      PIN_NUMBER='(N11,0,0)';
      BIDIRECTIONAL='TRUE';
      INPUT_LOAD='(-0.01,0.01)';
      OUTPUT_LOAD='(1.0,-1.0)';
    'PB34A':
      PIN_NUMBER='(R13,0,0)';
      BIDIRECTIONAL='TRUE';
      INPUT_LOAD='(-0.01,0.01)';
      OUTPUT_LOAD='(1.0,-1.0)';
    'PB34B':
      PIN_NUMBER='(T14,0,0)';
      BIDIRECTIONAL='TRUE';
      INPUT_LOAD='(-0.01,0.01)';
      OUTPUT_LOAD='(1.0,-1.0)';
    'PB35A':
      PIN_NUMBER='(R11,0,0)';
      BIDIRECTIONAL='TRUE';
      INPUT_LOAD='(-0.01,0.01)';
      OUTPUT_LOAD='(1.0,-1.0)';
    'PB35B':
      PIN_NUMBER='(T12,0,0)';
      BIDIRECTIONAL='TRUE';
      INPUT_LOAD='(-0.01,0.01)';
      OUTPUT_LOAD='(1.0,-1.0)';
    'PB37A':
      PIN_NUMBER='(P12,0,0)';
      BIDIRECTIONAL='TRUE';
      INPUT_LOAD='(-0.01,0.01)';
      OUTPUT_LOAD='(1.0,-1.0)';
    'PB37B':
      PIN_NUMBER='(T13,0,0)';
      BIDIRECTIONAL='TRUE';
      INPUT_LOAD='(-0.01,0.01)';
      OUTPUT_LOAD='(1.0,-1.0)';
    'PB38A_SN':
      PIN_NUMBER='(R12,0,0)';
      BIDIRECTIONAL='TRUE';
      INPUT_LOAD='(-0.01,0.01)';
      OUTPUT_LOAD='(1.0,-1.0)';
    'PB38B_SI_SISPI':
      PIN_NUMBER='(P13,0,0)';
      BIDIRECTIONAL='TRUE';
      INPUT_LOAD='(-0.01,0.01)';
      OUTPUT_LOAD='(1.0,-1.0)';
    'PB38C':
      PIN_NUMBER='(T15,0,0)';
      BIDIRECTIONAL='TRUE';
      INPUT_LOAD='(-0.01,0.01)';
      OUTPUT_LOAD='(1.0,-1.0)';
    'PB38D':
      PIN_NUMBER='(R14,0,0)';
      BIDIRECTIONAL='TRUE';
      INPUT_LOAD='(-0.01,0.01)';
      OUTPUT_LOAD='(1.0,-1.0)';
    'PB4A':
      PIN_NUMBER='(P4,0,0)';
      BIDIRECTIONAL='TRUE';
      INPUT_LOAD='(-0.01,0.01)';
      OUTPUT_LOAD='(1.0,-1.0)';
    'PB4B':
      PIN_NUMBER='(T4,0,0)';
      BIDIRECTIONAL='TRUE';
      INPUT_LOAD='(-0.01,0.01)';
      OUTPUT_LOAD='(1.0,-1.0)';
    'PB4C':
      PIN_NUMBER='(T2,0,0)';
      BIDIRECTIONAL='TRUE';
      INPUT_LOAD='(-0.01,0.01)';
      OUTPUT_LOAD='(1.0,-1.0)';
    'PB4D':
      PIN_NUMBER='(R3,0,0)';
      BIDIRECTIONAL='TRUE';
      INPUT_LOAD='(-0.01,0.01)';
      OUTPUT_LOAD='(1.0,-1.0)';
    'PB6A_CSSPIN':
      PIN_NUMBER='(R5,0,0)';
      BIDIRECTIONAL='TRUE';
      INPUT_LOAD='(-0.01,0.01)';
      OUTPUT_LOAD='(1.0,-1.0)';
    'PB6B':
      PIN_NUMBER='(P5,0,0)';
      BIDIRECTIONAL='TRUE';
      INPUT_LOAD='(-0.01,0.01)';
      OUTPUT_LOAD='(1.0,-1.0)';
    'PB7A':
      PIN_NUMBER='(T3,0,0)';
      BIDIRECTIONAL='TRUE';
      INPUT_LOAD='(-0.01,0.01)';
      OUTPUT_LOAD='(1.0,-1.0)';
    'PB7B':
      PIN_NUMBER='(R4,0,0)';
      BIDIRECTIONAL='TRUE';
      INPUT_LOAD='(-0.01,0.01)';
      OUTPUT_LOAD='(1.0,-1.0)';
    'PB9A':
      PIN_NUMBER='(T5,0,0)';
      BIDIRECTIONAL='TRUE';
      INPUT_LOAD='(-0.01,0.01)';
      OUTPUT_LOAD='(1.0,-1.0)';
    'PB9B':
      PIN_NUMBER='(R6,0,0)';
      BIDIRECTIONAL='TRUE';
      INPUT_LOAD='(-0.01,0.01)';
      OUTPUT_LOAD='(1.0,-1.0)';
    'PL10A':
      PIN_NUMBER='(G1,0,0)';
      BIDIRECTIONAL='TRUE';
      INPUT_LOAD='(-0.01,0.01)';
      OUTPUT_LOAD='(1.0,-1.0)';
    'PL10B':
      PIN_NUMBER='(H2,0,0)';
      BIDIRECTIONAL='TRUE';
      INPUT_LOAD='(-0.01,0.01)';
      OUTPUT_LOAD='(1.0,-1.0)';
    'PL10C':
      PIN_NUMBER='(H4,0,0)';
      BIDIRECTIONAL='TRUE';
      INPUT_LOAD='(-0.01,0.01)';
      OUTPUT_LOAD='(1.0,-1.0)';
    'PL10D':
      PIN_NUMBER='(J6,0,0)';
      BIDIRECTIONAL='TRUE';
      INPUT_LOAD='(-0.01,0.01)';
      OUTPUT_LOAD='(1.0,-1.0)';
    'PL11A':
      PIN_NUMBER='(H3,0,0)';
      BIDIRECTIONAL='TRUE';
      INPUT_LOAD='(-0.01,0.01)';
      OUTPUT_LOAD='(1.0,-1.0)';
    'PL11B':
      PIN_NUMBER='(H1,0,0)';
      BIDIRECTIONAL='TRUE';
      INPUT_LOAD='(-0.01,0.01)';
      OUTPUT_LOAD='(1.0,-1.0)';
    'PL12A_PCLKT4_0':
      PIN_NUMBER='(J1,0,0)';
      BIDIRECTIONAL='TRUE';
      INPUT_LOAD='(-0.01,0.01)';
      OUTPUT_LOAD='(1.0,-1.0)';
    'PL12B_PCLKC4_0':
      PIN_NUMBER='(J3,0,0)';
      BIDIRECTIONAL='TRUE';
      INPUT_LOAD='(-0.01,0.01)';
      OUTPUT_LOAD='(1.0,-1.0)';
    'PL15A':
      PIN_NUMBER='(J2,0,0)';
      BIDIRECTIONAL='TRUE';
      INPUT_LOAD='(-0.01,0.01)';
      OUTPUT_LOAD='(1.0,-1.0)';
    'PL15B':
      PIN_NUMBER='(K1,0,0)';
      BIDIRECTIONAL='TRUE';
      INPUT_LOAD='(-0.01,0.01)';
      OUTPUT_LOAD='(1.0,-1.0)';
    'PL15C':
      PIN_NUMBER='(H5,0,0)';
      BIDIRECTIONAL='TRUE';
      INPUT_LOAD='(-0.01,0.01)';
      OUTPUT_LOAD='(1.0,-1.0)';
    'PL15D':
      PIN_NUMBER='(J4,0,0)';
      BIDIRECTIONAL='TRUE';
      INPUT_LOAD='(-0.01,0.01)';
      OUTPUT_LOAD='(1.0,-1.0)';
    'PL16C':
      PIN_NUMBER='(J5,0,0)';
      BIDIRECTIONAL='TRUE';
      INPUT_LOAD='(-0.01,0.01)';
      OUTPUT_LOAD='(1.0,-1.0)';
    'PL16D':
      PIN_NUMBER='(K6,0,0)';
      BIDIRECTIONAL='TRUE';
      INPUT_LOAD='(-0.01,0.01)';
      OUTPUT_LOAD='(1.0,-1.0)';
    'PL17A':
      PIN_NUMBER='(K3,0,0)';
      BIDIRECTIONAL='TRUE';
      INPUT_LOAD='(-0.01,0.01)';
      OUTPUT_LOAD='(1.0,-1.0)';
    'PL17B':
      PIN_NUMBER='(K2,0,0)';
      BIDIRECTIONAL='TRUE';
      INPUT_LOAD='(-0.01,0.01)';
      OUTPUT_LOAD='(1.0,-1.0)';
    'PL19A':
      PIN_NUMBER='(L1,0,0)';
      BIDIRECTIONAL='TRUE';
      INPUT_LOAD='(-0.01,0.01)';
      OUTPUT_LOAD='(1.0,-1.0)';
    'PL19B':
      PIN_NUMBER='(L3,0,0)';
      BIDIRECTIONAL='TRUE';
      INPUT_LOAD='(-0.01,0.01)';
      OUTPUT_LOAD='(1.0,-1.0)';
    'PL19C':
      PIN_NUMBER='(K4,0,0)';
      BIDIRECTIONAL='TRUE';
      INPUT_LOAD='(-0.01,0.01)';
      OUTPUT_LOAD='(1.0,-1.0)';
    'PL19D':
      PIN_NUMBER='(L5,0,0)';
      BIDIRECTIONAL='TRUE';
      INPUT_LOAD='(-0.01,0.01)';
      OUTPUT_LOAD='(1.0,-1.0)';
    'PL21C':
      PIN_NUMBER='(K5,0,0)';
      BIDIRECTIONAL='TRUE';
      INPUT_LOAD='(-0.01,0.01)';
      OUTPUT_LOAD='(1.0,-1.0)';
    'PL21D':
      PIN_NUMBER='(L4,0,0)';
      BIDIRECTIONAL='TRUE';
      INPUT_LOAD='(-0.01,0.01)';
      OUTPUT_LOAD='(1.0,-1.0)';
    'PL22A_PCLKT3_0':
      PIN_NUMBER='(L2,0,0)';
      BIDIRECTIONAL='TRUE';
      INPUT_LOAD='(-0.01,0.01)';
      OUTPUT_LOAD='(1.0,-1.0)';
    'PL22B_PCLKC3_0':
      PIN_NUMBER='(M1,0,0)';
      BIDIRECTIONAL='TRUE';
      INPUT_LOAD='(-0.01,0.01)';
      OUTPUT_LOAD='(1.0,-1.0)';
    'PL23C':
      PIN_NUMBER='(N2,0,0)';
      BIDIRECTIONAL='TRUE';
      INPUT_LOAD='(-0.01,0.01)';
      OUTPUT_LOAD='(1.0,-1.0)';
    'PL23D':
      PIN_NUMBER='(P1,0,0)';
      BIDIRECTIONAL='TRUE';
      INPUT_LOAD='(-0.01,0.01)';
      OUTPUT_LOAD='(1.0,-1.0)';
    'PL24A':
      PIN_NUMBER='(M3,0,0)';
      BIDIRECTIONAL='TRUE';
      INPUT_LOAD='(-0.01,0.01)';
      OUTPUT_LOAD='(1.0,-1.0)';
    'PL24B':
      PIN_NUMBER='(N1,0,0)';
      BIDIRECTIONAL='TRUE';
      INPUT_LOAD='(-0.01,0.01)';
      OUTPUT_LOAD='(1.0,-1.0)';
    'PL25A':
      PIN_NUMBER='(M2,0,0)';
      BIDIRECTIONAL='TRUE';
      INPUT_LOAD='(-0.01,0.01)';
      OUTPUT_LOAD='(1.0,-1.0)';
    'PL25B':
      PIN_NUMBER='(N3,0,0)';
      BIDIRECTIONAL='TRUE';
      INPUT_LOAD='(-0.01,0.01)';
      OUTPUT_LOAD='(1.0,-1.0)';
    'PL25C':
      PIN_NUMBER='(R1,0,0)';
      BIDIRECTIONAL='TRUE';
      INPUT_LOAD='(-0.01,0.01)';
      OUTPUT_LOAD='(1.0,-1.0)';
    'PL25D':
      PIN_NUMBER='(P2,0,0)';
      BIDIRECTIONAL='TRUE';
      INPUT_LOAD='(-0.01,0.01)';
      OUTPUT_LOAD='(1.0,-1.0)';
    'PL2C':
      PIN_NUMBER='(B1,0,0)';
      BIDIRECTIONAL='TRUE';
      INPUT_LOAD='(-0.01,0.01)';
      OUTPUT_LOAD='(1.0,-1.0)';
    'PL2D':
      PIN_NUMBER='(C2,0,0)';
      BIDIRECTIONAL='TRUE';
      INPUT_LOAD='(-0.01,0.01)';
      OUTPUT_LOAD='(1.0,-1.0)';
    'PL3A_L_GPLLT_FB':
      PIN_NUMBER='(D3,0,0)';
      BIDIRECTIONAL='TRUE';
      INPUT_LOAD='(-0.01,0.01)';
      OUTPUT_LOAD='(1.0,-1.0)';
    'PL3B_L_GPLLC_FB':
      PIN_NUMBER='(D1,0,0)';
      BIDIRECTIONAL='TRUE';
      INPUT_LOAD='(-0.01,0.01)';
      OUTPUT_LOAD='(1.0,-1.0)';
    'PL4A_L_GPLLT_IN':
      PIN_NUMBER='(E2,0,0)';
      BIDIRECTIONAL='TRUE';
      INPUT_LOAD='(-0.01,0.01)';
      OUTPUT_LOAD='(1.0,-1.0)';
    'PL4B_L_GPLLC_IN':
      PIN_NUMBER='(E3,0,0)';
      BIDIRECTIONAL='TRUE';
      INPUT_LOAD='(-0.01,0.01)';
      OUTPUT_LOAD='(1.0,-1.0)';
    'PL4C':
      PIN_NUMBER='(C1,0,0)';
      BIDIRECTIONAL='TRUE';
      INPUT_LOAD='(-0.01,0.01)';
      OUTPUT_LOAD='(1.0,-1.0)';
    'PL4D':
      PIN_NUMBER='(D2,0,0)';
      BIDIRECTIONAL='TRUE';
      INPUT_LOAD='(-0.01,0.01)';
      OUTPUT_LOAD='(1.0,-1.0)';
    'PL6A_PCLKT5_0':
      PIN_NUMBER='(E1,0,0)';
      BIDIRECTIONAL='TRUE';
      INPUT_LOAD='(-0.01,0.01)';
      OUTPUT_LOAD='(1.0,-1.0)';
    'PL6B_PCLKC5_0':
      PIN_NUMBER='(F2,0,0)';
      BIDIRECTIONAL='TRUE';
      INPUT_LOAD='(-0.01,0.01)';
      OUTPUT_LOAD='(1.0,-1.0)';
    'PL6C':
      PIN_NUMBER='(F4,0,0)';
      BIDIRECTIONAL='TRUE';
      INPUT_LOAD='(-0.01,0.01)';
      OUTPUT_LOAD='(1.0,-1.0)';
    'PL6D':
      PIN_NUMBER='(G6,0,0)';
      BIDIRECTIONAL='TRUE';
      INPUT_LOAD='(-0.01,0.01)';
      OUTPUT_LOAD='(1.0,-1.0)';
    'PL7C':
      PIN_NUMBER='(G5,0,0)';
      BIDIRECTIONAL='TRUE';
      INPUT_LOAD='(-0.01,0.01)';
      OUTPUT_LOAD='(1.0,-1.0)';
    'PL7D':
      PIN_NUMBER='(G4,0,0)';
      BIDIRECTIONAL='TRUE';
      INPUT_LOAD='(-0.01,0.01)';
      OUTPUT_LOAD='(1.0,-1.0)';
    'PL8A':
      PIN_NUMBER='(F3,0,0)';
      BIDIRECTIONAL='TRUE';
      INPUT_LOAD='(-0.01,0.01)';
      OUTPUT_LOAD='(1.0,-1.0)';
    'PL8B':
      PIN_NUMBER='(F1,0,0)';
      BIDIRECTIONAL='TRUE';
      INPUT_LOAD='(-0.01,0.01)';
      OUTPUT_LOAD='(1.0,-1.0)';
    'PL9A':
      PIN_NUMBER='(G2,0,0)';
      BIDIRECTIONAL='TRUE';
      INPUT_LOAD='(-0.01,0.01)';
      OUTPUT_LOAD='(1.0,-1.0)';
    'PL9B':
      PIN_NUMBER='(G3,0,0)';
      BIDIRECTIONAL='TRUE';
      INPUT_LOAD='(-0.01,0.01)';
      OUTPUT_LOAD='(1.0,-1.0)';
    'PL9C':
      PIN_NUMBER='(F5,0,0)';
      BIDIRECTIONAL='TRUE';
      INPUT_LOAD='(-0.01,0.01)';
      OUTPUT_LOAD='(1.0,-1.0)';
    'PL9D':
      PIN_NUMBER='(H6,0,0)';
      BIDIRECTIONAL='TRUE';
      INPUT_LOAD='(-0.01,0.01)';
      OUTPUT_LOAD='(1.0,-1.0)';
    'PR10C':
      PIN_NUMBER='(0,G11,0)';
      BIDIRECTIONAL='TRUE';
      INPUT_LOAD='(-0.01,0.01)';
      OUTPUT_LOAD='(1.0,-1.0)';
    'PR10D':
      PIN_NUMBER='(0,H12,0)';
      BIDIRECTIONAL='TRUE';
      INPUT_LOAD='(-0.01,0.01)';
      OUTPUT_LOAD='(1.0,-1.0)';
    'PR11A':
      PIN_NUMBER='(0,G16,0)';
      BIDIRECTIONAL='TRUE';
      INPUT_LOAD='(-0.01,0.01)';
      OUTPUT_LOAD='(1.0,-1.0)';
    'PR11B':
      PIN_NUMBER='(0,H15,0)';
      BIDIRECTIONAL='TRUE';
      INPUT_LOAD='(-0.01,0.01)';
      OUTPUT_LOAD='(1.0,-1.0)';
    'PR11C':
      PIN_NUMBER='(0,H13,0)';
      BIDIRECTIONAL='TRUE';
      INPUT_LOAD='(-0.01,0.01)';
      OUTPUT_LOAD='(1.0,-1.0)';
    'PR11D':
      PIN_NUMBER='(0,J12,0)';
      BIDIRECTIONAL='TRUE';
      INPUT_LOAD='(-0.01,0.01)';
      OUTPUT_LOAD='(1.0,-1.0)';
    'PR12A_PCLKT1_0':
      PIN_NUMBER='(0,H14,0)';
      BIDIRECTIONAL='TRUE';
      INPUT_LOAD='(-0.01,0.01)';
      OUTPUT_LOAD='(1.0,-1.0)';
    'PR12B_PCLKC1_0':
      PIN_NUMBER='(0,H16,0)';
      BIDIRECTIONAL='TRUE';
      INPUT_LOAD='(-0.01,0.01)';
      OUTPUT_LOAD='(1.0,-1.0)';
    'PR15A':
      PIN_NUMBER='(0,J16,0)';
      BIDIRECTIONAL='TRUE';
      INPUT_LOAD='(-0.01,0.01)';
      OUTPUT_LOAD='(1.0,-1.0)';
    'PR15B':
      PIN_NUMBER='(0,J14,0)';
      BIDIRECTIONAL='TRUE';
      INPUT_LOAD='(-0.01,0.01)';
      OUTPUT_LOAD='(1.0,-1.0)';
    'PR16A':
      PIN_NUMBER='(0,J15,0)';
      BIDIRECTIONAL='TRUE';
      INPUT_LOAD='(-0.01,0.01)';
      OUTPUT_LOAD='(1.0,-1.0)';
    'PR16B':
      PIN_NUMBER='(0,K16,0)';
      BIDIRECTIONAL='TRUE';
      INPUT_LOAD='(-0.01,0.01)';
      OUTPUT_LOAD='(1.0,-1.0)';
    'PR16C':
      PIN_NUMBER='(0,H11,0)';
      BIDIRECTIONAL='TRUE';
      INPUT_LOAD='(-0.01,0.01)';
      OUTPUT_LOAD='(1.0,-1.0)';
    'PR16D':
      PIN_NUMBER='(0,J13,0)';
      BIDIRECTIONAL='TRUE';
      INPUT_LOAD='(-0.01,0.01)';
      OUTPUT_LOAD='(1.0,-1.0)';
    'PR17A':
      PIN_NUMBER='(0,K14,0)';
      BIDIRECTIONAL='TRUE';
      INPUT_LOAD='(-0.01,0.01)';
      OUTPUT_LOAD='(1.0,-1.0)';
    'PR17B':
      PIN_NUMBER='(0,K15,0)';
      BIDIRECTIONAL='TRUE';
      INPUT_LOAD='(-0.01,0.01)';
      OUTPUT_LOAD='(1.0,-1.0)';
    'PR17C':
      PIN_NUMBER='(0,J11,0)';
      BIDIRECTIONAL='TRUE';
      INPUT_LOAD='(-0.01,0.01)';
      OUTPUT_LOAD='(1.0,-1.0)';
    'PR17D':
      PIN_NUMBER='(0,L12,0)';
      BIDIRECTIONAL='TRUE';
      INPUT_LOAD='(-0.01,0.01)';
      OUTPUT_LOAD='(1.0,-1.0)';
    'PR18A':
      PIN_NUMBER='(0,L16,0)';
      BIDIRECTIONAL='TRUE';
      INPUT_LOAD='(-0.01,0.01)';
      OUTPUT_LOAD='(1.0,-1.0)';
    'PR18B':
      PIN_NUMBER='(0,L14,0)';
      BIDIRECTIONAL='TRUE';
      INPUT_LOAD='(-0.01,0.01)';
      OUTPUT_LOAD='(1.0,-1.0)';
    'PR19C':
      PIN_NUMBER='(0,K13,0)';
      BIDIRECTIONAL='TRUE';
      INPUT_LOAD='(-0.01,0.01)';
      OUTPUT_LOAD='(1.0,-1.0)';
    'PR19D':
      PIN_NUMBER='(0,K12,0)';
      BIDIRECTIONAL='TRUE';
      INPUT_LOAD='(-0.01,0.01)';
      OUTPUT_LOAD='(1.0,-1.0)';
    'PR21A':
      PIN_NUMBER='(0,L15,0)';
      BIDIRECTIONAL='TRUE';
      INPUT_LOAD='(-0.01,0.01)';
      OUTPUT_LOAD='(1.0,-1.0)';
    'PR21B':
      PIN_NUMBER='(0,M16,0)';
      BIDIRECTIONAL='TRUE';
      INPUT_LOAD='(-0.01,0.01)';
      OUTPUT_LOAD='(1.0,-1.0)';
    'PR21C':
      PIN_NUMBER='(0,K11,0)';
      BIDIRECTIONAL='TRUE';
      INPUT_LOAD='(-0.01,0.01)';
      OUTPUT_LOAD='(1.0,-1.0)';
    'PR21D':
      PIN_NUMBER='(0,L13,0)';
      BIDIRECTIONAL='TRUE';
      INPUT_LOAD='(-0.01,0.01)';
      OUTPUT_LOAD='(1.0,-1.0)';
    'PR23A':
      PIN_NUMBER='(0,M14,0)';
      BIDIRECTIONAL='TRUE';
      INPUT_LOAD='(-0.01,0.01)';
      OUTPUT_LOAD='(1.0,-1.0)';
    'PR23B':
      PIN_NUMBER='(0,M15,0)';
      BIDIRECTIONAL='TRUE';
      INPUT_LOAD='(-0.01,0.01)';
      OUTPUT_LOAD='(1.0,-1.0)';
    'PR23C':
      PIN_NUMBER='(0,N15,0)';
      BIDIRECTIONAL='TRUE';
      INPUT_LOAD='(-0.01,0.01)';
      OUTPUT_LOAD='(1.0,-1.0)';
    'PR23D':
      PIN_NUMBER='(0,P16,0)';
      BIDIRECTIONAL='TRUE';
      INPUT_LOAD='(-0.01,0.01)';
      OUTPUT_LOAD='(1.0,-1.0)';
    'PR24A':
      PIN_NUMBER='(0,N16,0)';
      BIDIRECTIONAL='TRUE';
      INPUT_LOAD='(-0.01,0.01)';
      OUTPUT_LOAD='(1.0,-1.0)';
    'PR24B':
      PIN_NUMBER='(0,N14,0)';
      BIDIRECTIONAL='TRUE';
      INPUT_LOAD='(-0.01,0.01)';
      OUTPUT_LOAD='(1.0,-1.0)';
    'PR25C':
      PIN_NUMBER='(0,P15,0)';
      BIDIRECTIONAL='TRUE';
      INPUT_LOAD='(-0.01,0.01)';
      OUTPUT_LOAD='(1.0,-1.0)';
    'PR25D':
      PIN_NUMBER='(0,R16,0)';
      BIDIRECTIONAL='TRUE';
      INPUT_LOAD='(-0.01,0.01)';
      OUTPUT_LOAD='(1.0,-1.0)';
    'PR2A_R_GPLLT_FB':
      PIN_NUMBER='(0,D14,0)';
      BIDIRECTIONAL='TRUE';
      INPUT_LOAD='(-0.01,0.01)';
      OUTPUT_LOAD='(1.0,-1.0)';
    'PR2B_R_GPLLC_FB':
      PIN_NUMBER='(0,E15,0)';
      BIDIRECTIONAL='TRUE';
      INPUT_LOAD='(-0.01,0.01)';
      OUTPUT_LOAD='(1.0,-1.0)';
    'PR2C':
      PIN_NUMBER='(0,C15,0)';
      BIDIRECTIONAL='TRUE';
      INPUT_LOAD='(-0.01,0.01)';
      OUTPUT_LOAD='(1.0,-1.0)';
    'PR2D':
      PIN_NUMBER='(0,B16,0)';
      BIDIRECTIONAL='TRUE';
      INPUT_LOAD='(-0.01,0.01)';
      OUTPUT_LOAD='(1.0,-1.0)';
    'PR3A_R_GPLLT_IN':
      PIN_NUMBER='(0,D16,0)';
      BIDIRECTIONAL='TRUE';
      INPUT_LOAD='(-0.01,0.01)';
      OUTPUT_LOAD='(1.0,-1.0)';
    'PR3B_R_GPLLC_IN':
      PIN_NUMBER='(0,E14,0)';
      BIDIRECTIONAL='TRUE';
      INPUT_LOAD='(-0.01,0.01)';
      OUTPUT_LOAD='(1.0,-1.0)';
    'PR4C':
      PIN_NUMBER='(0,C16,0)';
      BIDIRECTIONAL='TRUE';
      INPUT_LOAD='(-0.01,0.01)';
      OUTPUT_LOAD='(1.0,-1.0)';
    'PR4D':
      PIN_NUMBER='(0,D15,0)';
      BIDIRECTIONAL='TRUE';
      INPUT_LOAD='(-0.01,0.01)';
      OUTPUT_LOAD='(1.0,-1.0)';
    'PR5A':
      PIN_NUMBER='(0,E16,0)';
      BIDIRECTIONAL='TRUE';
      INPUT_LOAD='(-0.01,0.01)';
      OUTPUT_LOAD='(1.0,-1.0)';
    'PR5B':
      PIN_NUMBER='(0,F15,0)';
      BIDIRECTIONAL='TRUE';
      INPUT_LOAD='(-0.01,0.01)';
      OUTPUT_LOAD='(1.0,-1.0)';
    'PR6C':
      PIN_NUMBER='(0,F13,0)';
      BIDIRECTIONAL='TRUE';
      INPUT_LOAD='(-0.01,0.01)';
      OUTPUT_LOAD='(1.0,-1.0)';
    'PR6D':
      PIN_NUMBER='(0,G12,0)';
      BIDIRECTIONAL='TRUE';
      INPUT_LOAD='(-0.01,0.01)';
      OUTPUT_LOAD='(1.0,-1.0)';
    'PR7A':
      PIN_NUMBER='(0,F14,0)';
      BIDIRECTIONAL='TRUE';
      INPUT_LOAD='(-0.01,0.01)';
      OUTPUT_LOAD='(1.0,-1.0)';
    'PR7B':
      PIN_NUMBER='(0,F16,0)';
      BIDIRECTIONAL='TRUE';
      INPUT_LOAD='(-0.01,0.01)';
      OUTPUT_LOAD='(1.0,-1.0)';
    'PR7C':
      PIN_NUMBER='(0,F12,0)';
      BIDIRECTIONAL='TRUE';
      INPUT_LOAD='(-0.01,0.01)';
      OUTPUT_LOAD='(1.0,-1.0)';
    'PR7D':
      PIN_NUMBER='(0,G13,0)';
      BIDIRECTIONAL='TRUE';
      INPUT_LOAD='(-0.01,0.01)';
      OUTPUT_LOAD='(1.0,-1.0)';
    'PR9A':
      PIN_NUMBER='(0,G15,0)';
      BIDIRECTIONAL='TRUE';
      INPUT_LOAD='(-0.01,0.01)';
      OUTPUT_LOAD='(1.0,-1.0)';
    'PR9B':
      PIN_NUMBER='(0,G14,0)';
      BIDIRECTIONAL='TRUE';
      INPUT_LOAD='(-0.01,0.01)';
      OUTPUT_LOAD='(1.0,-1.0)';
    'PT10A':
      PIN_NUMBER='(0,A4,0)';
      BIDIRECTIONAL='TRUE';
      INPUT_LOAD='(-0.01,0.01)';
      OUTPUT_LOAD='(1.0,-1.0)';
    'PT10B':
      PIN_NUMBER='(0,C5,0)';
      BIDIRECTIONAL='TRUE';
      INPUT_LOAD='(-0.01,0.01)';
      OUTPUT_LOAD='(1.0,-1.0)';
    'PT11A':
      PIN_NUMBER='(0,A5,0)';
      BIDIRECTIONAL='TRUE';
      INPUT_LOAD='(-0.01,0.01)';
      OUTPUT_LOAD='(1.0,-1.0)';
    'PT11B':
      PIN_NUMBER='(0,B6,0)';
      BIDIRECTIONAL='TRUE';
      INPUT_LOAD='(-0.01,0.01)';
      OUTPUT_LOAD='(1.0,-1.0)';
    'PT12A':
      PIN_NUMBER='(0,A3,0)';
      BIDIRECTIONAL='TRUE';
      INPUT_LOAD='(-0.01,0.01)';
      OUTPUT_LOAD='(1.0,-1.0)';
    'PT12B':
      PIN_NUMBER='(0,B4,0)';
      BIDIRECTIONAL='TRUE';
      INPUT_LOAD='(-0.01,0.01)';
      OUTPUT_LOAD='(1.0,-1.0)';
    'PT14A':
      PIN_NUMBER='(0,D6,0)';
      BIDIRECTIONAL='TRUE';
      INPUT_LOAD='(-0.01,0.01)';
      OUTPUT_LOAD='(1.0,-1.0)';
    'PT14B':
      PIN_NUMBER='(0,E7,0)';
      BIDIRECTIONAL='TRUE';
      INPUT_LOAD='(-0.01,0.01)';
      OUTPUT_LOAD='(1.0,-1.0)';
    'PT14C_TDO':
      PIN_NUMBER='(0,C6,0)';
      BIDIRECTIONAL='TRUE';
      INPUT_LOAD='(-0.01,0.01)';
      OUTPUT_LOAD='(1.0,-1.0)';
    'PT14D_TDI':
      PIN_NUMBER='(0,A6,0)';
      BIDIRECTIONAL='TRUE';
      INPUT_LOAD='(-0.01,0.01)';
      OUTPUT_LOAD='(1.0,-1.0)';
    'PT15A':
      PIN_NUMBER='(0,B7,0)';
      BIDIRECTIONAL='TRUE';
      INPUT_LOAD='(-0.01,0.01)';
      OUTPUT_LOAD='(1.0,-1.0)';
    'PT15B':
      PIN_NUMBER='(0,C7,0)';
      BIDIRECTIONAL='TRUE';
      INPUT_LOAD='(-0.01,0.01)';
      OUTPUT_LOAD='(1.0,-1.0)';
    'PT16A':
      PIN_NUMBER='(0,E6,0)';
      BIDIRECTIONAL='TRUE';
      INPUT_LOAD='(-0.01,0.01)';
      OUTPUT_LOAD='(1.0,-1.0)';
    'PT16B':
      PIN_NUMBER='(0,D7,0)';
      BIDIRECTIONAL='TRUE';
      INPUT_LOAD='(-0.01,0.01)';
      OUTPUT_LOAD='(1.0,-1.0)';
    'PT17A':
      PIN_NUMBER='(0,F7,0)';
      BIDIRECTIONAL='TRUE';
      INPUT_LOAD='(-0.01,0.01)';
      OUTPUT_LOAD='(1.0,-1.0)';
    'PT17B':
      PIN_NUMBER='(0,E8,0)';
      BIDIRECTIONAL='TRUE';
      INPUT_LOAD='(-0.01,0.01)';
      OUTPUT_LOAD='(1.0,-1.0)';
    'PT17C_TCK':
      PIN_NUMBER='(0,A7,0)';
      BIDIRECTIONAL='TRUE';
      INPUT_LOAD='(-0.01,0.01)';
      OUTPUT_LOAD='(1.0,-1.0)';
    'PT17D_TMS':
      PIN_NUMBER='(0,B8,0)';
      BIDIRECTIONAL='TRUE';
      INPUT_LOAD='(-0.01,0.01)';
      OUTPUT_LOAD='(1.0,-1.0)';
    'PT18A_PCLKT0_1':
      PIN_NUMBER='(0,C8,0)';
      BIDIRECTIONAL='TRUE';
      INPUT_LOAD='(-0.01,0.01)';
      OUTPUT_LOAD='(1.0,-1.0)';
    'PT18B_PCLKC0_1':
      PIN_NUMBER='(0,A8,0)';
      BIDIRECTIONAL='TRUE';
      INPUT_LOAD='(-0.01,0.01)';
      OUTPUT_LOAD='(1.0,-1.0)';
    'PT21A':
      PIN_NUMBER='(0,D8,0)';
      BIDIRECTIONAL='TRUE';
      INPUT_LOAD='(-0.01,0.01)';
      OUTPUT_LOAD='(1.0,-1.0)';
    'PT21B':
      PIN_NUMBER='(0,E9,0)';
      BIDIRECTIONAL='TRUE';
      INPUT_LOAD='(-0.01,0.01)';
      OUTPUT_LOAD='(1.0,-1.0)';
    'PT22A':
      PIN_NUMBER='(0,F8,0)';
      BIDIRECTIONAL='TRUE';
      INPUT_LOAD='(-0.01,0.01)';
      OUTPUT_LOAD='(1.0,-1.0)';
    'PT22B':
      PIN_NUMBER='(0,D9,0)';
      BIDIRECTIONAL='TRUE';
      INPUT_LOAD='(-0.01,0.01)';
      OUTPUT_LOAD='(1.0,-1.0)';
    'PT22C_SCL_PCLKT0_0':
      PIN_NUMBER='(0,A9,0)';
      BIDIRECTIONAL='TRUE';
      INPUT_LOAD='(-0.01,0.01)';
      OUTPUT_LOAD='(1.0,-1.0)';
    'PT22D_SDA_PCLKC0_0':
      PIN_NUMBER='(0,C9,0)';
      BIDIRECTIONAL='TRUE';
      INPUT_LOAD='(-0.01,0.01)';
      OUTPUT_LOAD='(1.0,-1.0)';
    'PT25A':
      PIN_NUMBER='(0,B9,0)';
      BIDIRECTIONAL='TRUE';
      INPUT_LOAD='(-0.01,0.01)';
      OUTPUT_LOAD='(1.0,-1.0)';
    'PT25B':
      PIN_NUMBER='(0,A10,0)';
      BIDIRECTIONAL='TRUE';
      INPUT_LOAD='(-0.01,0.01)';
      OUTPUT_LOAD='(1.0,-1.0)';
    'PT26A':
      PIN_NUMBER='(0,F9,0)';
      BIDIRECTIONAL='TRUE';
      INPUT_LOAD='(-0.01,0.01)';
      OUTPUT_LOAD='(1.0,-1.0)';
    'PT26B':
      PIN_NUMBER='(0,E11,0)';
      BIDIRECTIONAL='TRUE';
      INPUT_LOAD='(-0.01,0.01)';
      OUTPUT_LOAD='(1.0,-1.0)';
    'PT27A':
      PIN_NUMBER='(0,D10,0)';
      BIDIRECTIONAL='TRUE';
      INPUT_LOAD='(-0.01,0.01)';
      OUTPUT_LOAD='(1.0,-1.0)';
    'PT27B':
      PIN_NUMBER='(0,E10,0)';
      BIDIRECTIONAL='TRUE';
      INPUT_LOAD='(-0.01,0.01)';
      OUTPUT_LOAD='(1.0,-1.0)';
    'PT27C_JTAGENB':
      PIN_NUMBER='(0,C10,0)';
      BIDIRECTIONAL='TRUE';
      INPUT_LOAD='(-0.01,0.01)';
      OUTPUT_LOAD='(1.0,-1.0)';
    'PT27D_PROGRAMN':
      PIN_NUMBER='(0,B10,0)';
      BIDIRECTIONAL='TRUE';
      INPUT_LOAD='(-0.01,0.01)';
      OUTPUT_LOAD='(1.0,-1.0)';
    'PT28A':
      PIN_NUMBER='(0,A11,0)';
      BIDIRECTIONAL='TRUE';
      INPUT_LOAD='(-0.01,0.01)';
      OUTPUT_LOAD='(1.0,-1.0)';
    'PT28B':
      PIN_NUMBER='(0,C11,0)';
      BIDIRECTIONAL='TRUE';
      INPUT_LOAD='(-0.01,0.01)';
      OUTPUT_LOAD='(1.0,-1.0)';
    'PT32A':
      PIN_NUMBER='(0,F10,0)';
      BIDIRECTIONAL='TRUE';
      INPUT_LOAD='(-0.01,0.01)';
      OUTPUT_LOAD='(1.0,-1.0)';
    'PT32B':
      PIN_NUMBER='(0,D11,0)';
      BIDIRECTIONAL='TRUE';
      INPUT_LOAD='(-0.01,0.01)';
      OUTPUT_LOAD='(1.0,-1.0)';
    'PT33A':
      PIN_NUMBER='(0,B11,0)';
      BIDIRECTIONAL='TRUE';
      INPUT_LOAD='(-0.01,0.01)';
      OUTPUT_LOAD='(1.0,-1.0)';
    'PT33B':
      PIN_NUMBER='(0,A12,0)';
      BIDIRECTIONAL='TRUE';
      INPUT_LOAD='(-0.01,0.01)';
      OUTPUT_LOAD='(1.0,-1.0)';
    'PT34A':
      PIN_NUMBER='(0,B13,0)';
      BIDIRECTIONAL='TRUE';
      INPUT_LOAD='(-0.01,0.01)';
      OUTPUT_LOAD='(1.0,-1.0)';
    'PT34B':
      PIN_NUMBER='(0,A14,0)';
      BIDIRECTIONAL='TRUE';
      INPUT_LOAD='(-0.01,0.01)';
      OUTPUT_LOAD='(1.0,-1.0)';
    'PT35A':
      PIN_NUMBER='(0,C12,0)';
      BIDIRECTIONAL='TRUE';
      INPUT_LOAD='(-0.01,0.01)';
      OUTPUT_LOAD='(1.0,-1.0)';
    'PT35B':
      PIN_NUMBER='(0,B12,0)';
      BIDIRECTIONAL='TRUE';
      INPUT_LOAD='(-0.01,0.01)';
      OUTPUT_LOAD='(1.0,-1.0)';
    'PT36A':
      PIN_NUMBER='(0,B14,0)';
      BIDIRECTIONAL='TRUE';
      INPUT_LOAD='(-0.01,0.01)';
      OUTPUT_LOAD='(1.0,-1.0)';
    'PT36B':
      PIN_NUMBER='(0,A15,0)';
      BIDIRECTIONAL='TRUE';
      INPUT_LOAD='(-0.01,0.01)';
      OUTPUT_LOAD='(1.0,-1.0)';
    'PT36C_INITN':
      PIN_NUMBER='(0,A13,0)';
      BIDIRECTIONAL='TRUE';
      INPUT_LOAD='(-0.01,0.01)';
      OUTPUT_LOAD='(1.0,-1.0)';
    'PT36D_DONE':
      PIN_NUMBER='(0,C13,0)';
      BIDIRECTIONAL='TRUE';
      INPUT_LOAD='(-0.01,0.01)';
      OUTPUT_LOAD='(1.0,-1.0)';
    'PT9A':
      PIN_NUMBER='(0,C4,0)';
      BIDIRECTIONAL='TRUE';
      INPUT_LOAD='(-0.01,0.01)';
      OUTPUT_LOAD='(1.0,-1.0)';
    'PT9B':
      PIN_NUMBER='(0,B5,0)';
      BIDIRECTIONAL='TRUE';
      INPUT_LOAD='(-0.01,0.01)';
      OUTPUT_LOAD='(1.0,-1.0)';
    'PT9C':
      PIN_NUMBER='(0,B3,0)';
      BIDIRECTIONAL='TRUE';
      INPUT_LOAD='(-0.01,0.01)';
      OUTPUT_LOAD='(1.0,-1.0)';
    'VCC'<7>:
      PIN_NUMBER='(0,0,K10)';
      PINUSE='POWER';
      NO_LOAD_CHECK='Both';
      NO_IO_CHECK='Both';
      NO_ASSERT_CHECK='TRUE';
      NO_DIR_CHECK='TRUE';
      ALLOW_CONNECT='TRUE';
    'VCC'<6>:
      PIN_NUMBER='(0,0,K7)';
      PINUSE='POWER';
      NO_LOAD_CHECK='Both';
      NO_IO_CHECK='Both';
      NO_ASSERT_CHECK='TRUE';
      NO_DIR_CHECK='TRUE';
      ALLOW_CONNECT='TRUE';
    'VCC'<5>:
      PIN_NUMBER='(0,0,G10)';
      PINUSE='POWER';
      NO_LOAD_CHECK='Both';
      NO_IO_CHECK='Both';
      NO_ASSERT_CHECK='TRUE';
      NO_DIR_CHECK='TRUE';
      ALLOW_CONNECT='TRUE';
    'VCC'<4>:
      PIN_NUMBER='(0,0,G7)';
      PINUSE='POWER';
      NO_LOAD_CHECK='Both';
      NO_IO_CHECK='Both';
      NO_ASSERT_CHECK='TRUE';
      NO_DIR_CHECK='TRUE';
      ALLOW_CONNECT='TRUE';
    'VCC'<3>:
      PIN_NUMBER='(0,0,T16)';
      PINUSE='POWER';
      NO_LOAD_CHECK='Both';
      NO_IO_CHECK='Both';
      NO_ASSERT_CHECK='TRUE';
      NO_DIR_CHECK='TRUE';
      ALLOW_CONNECT='TRUE';
    'VCC'<2>:
      PIN_NUMBER='(0,0,T1)';
      PINUSE='POWER';
      NO_LOAD_CHECK='Both';
      NO_IO_CHECK='Both';
      NO_ASSERT_CHECK='TRUE';
      NO_DIR_CHECK='TRUE';
      ALLOW_CONNECT='TRUE';
    'VCC'<1>:
      PIN_NUMBER='(0,0,A16)';
      PINUSE='POWER';
      NO_LOAD_CHECK='Both';
      NO_IO_CHECK='Both';
      NO_ASSERT_CHECK='TRUE';
      NO_DIR_CHECK='TRUE';
      ALLOW_CONNECT='TRUE';
    'VCC'<0>:
      PIN_NUMBER='(0,0,A1)';
      PINUSE='POWER';
      NO_LOAD_CHECK='Both';
      NO_IO_CHECK='Both';
      NO_ASSERT_CHECK='TRUE';
      NO_DIR_CHECK='TRUE';
      ALLOW_CONNECT='TRUE';
    'VCCIO0'<3>:
      PIN_NUMBER='(0,0,G9)';
      PINUSE='POWER';
      NO_LOAD_CHECK='Both';
      NO_IO_CHECK='Both';
      NO_ASSERT_CHECK='TRUE';
      NO_DIR_CHECK='TRUE';
      ALLOW_CONNECT='TRUE';
    'VCCIO0'<2>:
      PIN_NUMBER='(0,0,G8)';
      PINUSE='POWER';
      NO_LOAD_CHECK='Both';
      NO_IO_CHECK='Both';
      NO_ASSERT_CHECK='TRUE';
      NO_DIR_CHECK='TRUE';
      ALLOW_CONNECT='TRUE';
    'VCCIO0'<1>:
      PIN_NUMBER='(0,0,D5)';
      PINUSE='POWER';
      NO_LOAD_CHECK='Both';
      NO_IO_CHECK='Both';
      NO_ASSERT_CHECK='TRUE';
      NO_DIR_CHECK='TRUE';
      ALLOW_CONNECT='TRUE';
    'VCCIO0'<0>:
      PIN_NUMBER='(0,0,D12)';
      PINUSE='POWER';
      NO_LOAD_CHECK='Both';
      NO_IO_CHECK='Both';
      NO_ASSERT_CHECK='TRUE';
      NO_DIR_CHECK='TRUE';
      ALLOW_CONNECT='TRUE';
    'VCCIO1'<3>:
      PIN_NUMBER='(0,0,M13)';
      PINUSE='POWER';
      NO_LOAD_CHECK='Both';
      NO_IO_CHECK='Both';
      NO_ASSERT_CHECK='TRUE';
      NO_DIR_CHECK='TRUE';
      ALLOW_CONNECT='TRUE';
    'VCCIO1'<2>:
      PIN_NUMBER='(0,0,J10)';
      PINUSE='POWER';
      NO_LOAD_CHECK='Both';
      NO_IO_CHECK='Both';
      NO_ASSERT_CHECK='TRUE';
      NO_DIR_CHECK='TRUE';
      ALLOW_CONNECT='TRUE';
    'VCCIO1'<1>:
      PIN_NUMBER='(0,0,H10)';
      PINUSE='POWER';
      NO_LOAD_CHECK='Both';
      NO_IO_CHECK='Both';
      NO_ASSERT_CHECK='TRUE';
      NO_DIR_CHECK='TRUE';
      ALLOW_CONNECT='TRUE';
    'VCCIO1'<0>:
      PIN_NUMBER='(0,0,E13)';
      PINUSE='POWER';
      NO_LOAD_CHECK='Both';
      NO_IO_CHECK='Both';
      NO_ASSERT_CHECK='TRUE';
      NO_DIR_CHECK='TRUE';
      ALLOW_CONNECT='TRUE';
    'VCCIO2'<3>:
      PIN_NUMBER='(0,0,N12)';
      PINUSE='POWER';
      NO_LOAD_CHECK='Both';
      NO_IO_CHECK='Both';
      NO_ASSERT_CHECK='TRUE';
      NO_DIR_CHECK='TRUE';
      ALLOW_CONNECT='TRUE';
    'VCCIO2'<2>:
      PIN_NUMBER='(0,0,N5)';
      PINUSE='POWER';
      NO_LOAD_CHECK='Both';
      NO_IO_CHECK='Both';
      NO_ASSERT_CHECK='TRUE';
      NO_DIR_CHECK='TRUE';
      ALLOW_CONNECT='TRUE';
    'VCCIO2'<1>:
      PIN_NUMBER='(0,0,K9)';
      PINUSE='POWER';
      NO_LOAD_CHECK='Both';
      NO_IO_CHECK='Both';
      NO_ASSERT_CHECK='TRUE';
      NO_DIR_CHECK='TRUE';
      ALLOW_CONNECT='TRUE';
    'VCCIO2'<0>:
      PIN_NUMBER='(0,0,K8)';
      PINUSE='POWER';
      NO_LOAD_CHECK='Both';
      NO_IO_CHECK='Both';
      NO_ASSERT_CHECK='TRUE';
      NO_DIR_CHECK='TRUE';
      ALLOW_CONNECT='TRUE';
    'VCCIO3<0>':
      PIN_NUMBER='(0,0,M4)';
      PINUSE='POWER';
      NO_LOAD_CHECK='Both';
      NO_IO_CHECK='Both';
      NO_ASSERT_CHECK='TRUE';
      NO_DIR_CHECK='TRUE';
      ALLOW_CONNECT='TRUE';
    'VCCIO4'<1>:
      PIN_NUMBER='(0,0,J7)';
      PINUSE='POWER';
      NO_LOAD_CHECK='Both';
      NO_IO_CHECK='Both';
      NO_ASSERT_CHECK='TRUE';
      NO_DIR_CHECK='TRUE';
      ALLOW_CONNECT='TRUE';
    'VCCIO4'<0>:
      PIN_NUMBER='(0,0,H7)';
      PINUSE='POWER';
      NO_LOAD_CHECK='Both';
      NO_IO_CHECK='Both';
      NO_ASSERT_CHECK='TRUE';
      NO_DIR_CHECK='TRUE';
      ALLOW_CONNECT='TRUE';
    'VCCIO5<0>':
      PIN_NUMBER='(0,0,E4)';
      PINUSE='POWER';
      NO_LOAD_CHECK='Both';
      NO_IO_CHECK='Both';
      NO_ASSERT_CHECK='TRUE';
      NO_DIR_CHECK='TRUE';
      ALLOW_CONNECT='TRUE';
  end_pin;
  body
    PART_NAME='LCMXO2_A';
    PHYS_DES_PREFIX='U';
  end_body;
end_primitive;
primitive 'LCMXO2_A_SM2';
  pin
    'PL2C':
      PIN_NUMBER='(1)';
      BIDIRECTIONAL='TRUE';
      INPUT_LOAD='(-0.01,0.01)';
      OUTPUT_LOAD='(1.0,-1.0)';
    'PL2D':
      PIN_NUMBER='(2)';
      BIDIRECTIONAL='TRUE';
      INPUT_LOAD='(-0.01,0.01)';
      OUTPUT_LOAD='(1.0,-1.0)';
    'PL3A':
      PIN_NUMBER='(3)';
      BIDIRECTIONAL='TRUE';
      INPUT_LOAD='(-0.01,0.01)';
      OUTPUT_LOAD='(1.0,-1.0)';
    'PL3B':
      PIN_NUMBER='(4)';
      BIDIRECTIONAL='TRUE';
      INPUT_LOAD='(-0.01,0.01)';
      OUTPUT_LOAD='(1.0,-1.0)';
    'PL3C':
      PIN_NUMBER='(7)';
      BIDIRECTIONAL='TRUE';
      INPUT_LOAD='(-0.01,0.01)';
      OUTPUT_LOAD='(1.0,-1.0)';
    'PL3D':
      PIN_NUMBER='(8)';
      BIDIRECTIONAL='TRUE';
      INPUT_LOAD='(-0.01,0.01)';
      OUTPUT_LOAD='(1.0,-1.0)';
    'PL4A':
      PIN_NUMBER='(9)';
      BIDIRECTIONAL='TRUE';
      INPUT_LOAD='(-0.01,0.01)';
      OUTPUT_LOAD='(1.0,-1.0)';
    'PL4B':
      PIN_NUMBER='(10)';
      BIDIRECTIONAL='TRUE';
      INPUT_LOAD='(-0.01,0.01)';
      OUTPUT_LOAD='(1.0,-1.0)';
    'PL5A':
      PIN_NUMBER='(12)';
      BIDIRECTIONAL='TRUE';
      INPUT_LOAD='(-0.01,0.01)';
      OUTPUT_LOAD='(1.0,-1.0)';
    'PL5B':
      PIN_NUMBER='(13)';
      BIDIRECTIONAL='TRUE';
      INPUT_LOAD='(-0.01,0.01)';
      OUTPUT_LOAD='(1.0,-1.0)';
    'PL5C':
      PIN_NUMBER='(14)';
      BIDIRECTIONAL='TRUE';
      INPUT_LOAD='(-0.01,0.01)';
      OUTPUT_LOAD='(1.0,-1.0)';
    'PL5D':
      PIN_NUMBER='(15)';
      BIDIRECTIONAL='TRUE';
      INPUT_LOAD='(-0.01,0.01)';
      OUTPUT_LOAD='(1.0,-1.0)';
    'PL8A':
      PIN_NUMBER='(16)';
      BIDIRECTIONAL='TRUE';
      INPUT_LOAD='(-0.01,0.01)';
      OUTPUT_LOAD='(1.0,-1.0)';
    'PL8B':
      PIN_NUMBER='(17)';
      BIDIRECTIONAL='TRUE';
      INPUT_LOAD='(-0.01,0.01)';
      OUTPUT_LOAD='(1.0,-1.0)';
    'PL8C':
      PIN_NUMBER='(18)';
      BIDIRECTIONAL='TRUE';
      INPUT_LOAD='(-0.01,0.01)';
      OUTPUT_LOAD='(1.0,-1.0)';
    'PL8D':
      PIN_NUMBER='(19)';
      BIDIRECTIONAL='TRUE';
      INPUT_LOAD='(-0.01,0.01)';
      OUTPUT_LOAD='(1.0,-1.0)';
    'PL9A':
      PIN_NUMBER='(20)';
      BIDIRECTIONAL='TRUE';
      INPUT_LOAD='(-0.01,0.01)';
      OUTPUT_LOAD='(1.0,-1.0)';
    'PL9B':
      PIN_NUMBER='(21)';
      BIDIRECTIONAL='TRUE';
      INPUT_LOAD='(-0.01,0.01)';
      OUTPUT_LOAD='(1.0,-1.0)';
    'PL10C':
      PIN_NUMBER='(24)';
      BIDIRECTIONAL='TRUE';
      INPUT_LOAD='(-0.01,0.01)';
      OUTPUT_LOAD='(1.0,-1.0)';
    'PL10D':
      PIN_NUMBER='(25)';
      BIDIRECTIONAL='TRUE';
      INPUT_LOAD='(-0.01,0.01)';
      OUTPUT_LOAD='(1.0,-1.0)';
    'PB4C':
      PIN_NUMBER='(27)';
      BIDIRECTIONAL='TRUE';
      INPUT_LOAD='(-0.01,0.01)';
      OUTPUT_LOAD='(1.0,-1.0)';
    'PB4D':
      PIN_NUMBER='(28)';
      BIDIRECTIONAL='TRUE';
      INPUT_LOAD='(-0.01,0.01)';
      OUTPUT_LOAD='(1.0,-1.0)';
    'PB6A':
      PIN_NUMBER='(29)';
      BIDIRECTIONAL='TRUE';
      INPUT_LOAD='(-0.01,0.01)';
      OUTPUT_LOAD='(1.0,-1.0)';
    'PB6B':
      PIN_NUMBER='(30)';
      BIDIRECTIONAL='TRUE';
      INPUT_LOAD='(-0.01,0.01)';
      OUTPUT_LOAD='(1.0,-1.0)';
    'PB6C':
      PIN_NUMBER='(31)';
      BIDIRECTIONAL='TRUE';
      INPUT_LOAD='(-0.01,0.01)';
      OUTPUT_LOAD='(1.0,-1.0)';
    'PB6D':
      PIN_NUMBER='(32)';
      BIDIRECTIONAL='TRUE';
      INPUT_LOAD='(-0.01,0.01)';
      OUTPUT_LOAD='(1.0,-1.0)';
    'PB9A':
      PIN_NUMBER='(34)';
      BIDIRECTIONAL='TRUE';
      INPUT_LOAD='(-0.01,0.01)';
      OUTPUT_LOAD='(1.0,-1.0)';
    'PB9B':
      PIN_NUMBER='(35)';
      BIDIRECTIONAL='TRUE';
      INPUT_LOAD='(-0.01,0.01)';
      OUTPUT_LOAD='(1.0,-1.0)';
    'PB11C':
      PIN_NUMBER='(36)';
      BIDIRECTIONAL='TRUE';
      INPUT_LOAD='(-0.01,0.01)';
      OUTPUT_LOAD='(1.0,-1.0)';
    'PB11D':
      PIN_NUMBER='(37)';
      BIDIRECTIONAL='TRUE';
      INPUT_LOAD='(-0.01,0.01)';
      OUTPUT_LOAD='(1.0,-1.0)';
    'PB11A':
      PIN_NUMBER='(38)';
      BIDIRECTIONAL='TRUE';
      INPUT_LOAD='(-0.01,0.01)';
      OUTPUT_LOAD='(1.0,-1.0)';
    'PB11B':
      PIN_NUMBER='(39)';
      BIDIRECTIONAL='TRUE';
      INPUT_LOAD='(-0.01,0.01)';
      OUTPUT_LOAD='(1.0,-1.0)';
    'PB15A':
      PIN_NUMBER='(40)';
      BIDIRECTIONAL='TRUE';
      INPUT_LOAD='(-0.01,0.01)';
      OUTPUT_LOAD='(1.0,-1.0)';
    'PB15B':
      PIN_NUMBER='(41)';
      BIDIRECTIONAL='TRUE';
      INPUT_LOAD='(-0.01,0.01)';
      OUTPUT_LOAD='(1.0,-1.0)';
    'PB18A':
      PIN_NUMBER='(42)';
      BIDIRECTIONAL='TRUE';
      INPUT_LOAD='(-0.01,0.01)';
      OUTPUT_LOAD='(1.0,-1.0)';
    'PB18B':
      PIN_NUMBER='(43)';
      BIDIRECTIONAL='TRUE';
      INPUT_LOAD='(-0.01,0.01)';
      OUTPUT_LOAD='(1.0,-1.0)';
    'PB18C':
      PIN_NUMBER='(45)';
      BIDIRECTIONAL='TRUE';
      INPUT_LOAD='(-0.01,0.01)';
      OUTPUT_LOAD='(1.0,-1.0)';
    'PB18D':
      PIN_NUMBER='(47)';
      BIDIRECTIONAL='TRUE';
      INPUT_LOAD='(-0.01,0.01)';
      OUTPUT_LOAD='(1.0,-1.0)';
    'PB20C':
      PIN_NUMBER='(48)';
      BIDIRECTIONAL='TRUE';
      INPUT_LOAD='(-0.01,0.01)';
      OUTPUT_LOAD='(1.0,-1.0)';
    'PB20D':
      PIN_NUMBER='(49)';
      BIDIRECTIONAL='TRUE';
      INPUT_LOAD='(-0.01,0.01)';
      OUTPUT_LOAD='(1.0,-1.0)';
    'PR10D':
      PIN_NUMBER='(51)';
      BIDIRECTIONAL='TRUE';
      INPUT_LOAD='(-0.01,0.01)';
      OUTPUT_LOAD='(1.0,-1.0)';
    'PR10C':
      PIN_NUMBER='(52)';
      BIDIRECTIONAL='TRUE';
      INPUT_LOAD='(-0.01,0.01)';
      OUTPUT_LOAD='(1.0,-1.0)';
    'PR9D':
      PIN_NUMBER='(53)';
      BIDIRECTIONAL='TRUE';
      INPUT_LOAD='(-0.01,0.01)';
      OUTPUT_LOAD='(1.0,-1.0)';
    'PR9C':
      PIN_NUMBER='(54)';
      BIDIRECTIONAL='TRUE';
      INPUT_LOAD='(-0.01,0.01)';
      OUTPUT_LOAD='(1.0,-1.0)';
    'PR9B':
      PIN_NUMBER='(57)';
      BIDIRECTIONAL='TRUE';
      INPUT_LOAD='(-0.01,0.01)';
      OUTPUT_LOAD='(1.0,-1.0)';
    'PR9A':
      PIN_NUMBER='(58)';
      BIDIRECTIONAL='TRUE';
      INPUT_LOAD='(-0.01,0.01)';
      OUTPUT_LOAD='(1.0,-1.0)';
    'PR8D':
      PIN_NUMBER='(59)';
      BIDIRECTIONAL='TRUE';
      INPUT_LOAD='(-0.01,0.01)';
      OUTPUT_LOAD='(1.0,-1.0)';
    'PR8C':
      PIN_NUMBER='(60)';
      BIDIRECTIONAL='TRUE';
      INPUT_LOAD='(-0.01,0.01)';
      OUTPUT_LOAD='(1.0,-1.0)';
    'PR8A':
      PIN_NUMBER='(61)';
      BIDIRECTIONAL='TRUE';
      INPUT_LOAD='(-0.01,0.01)';
      OUTPUT_LOAD='(1.0,-1.0)';
    'PR5D':
      PIN_NUMBER='(62)';
      BIDIRECTIONAL='TRUE';
      INPUT_LOAD='(-0.01,0.01)';
      OUTPUT_LOAD='(1.0,-1.0)';
    'PR5C':
      PIN_NUMBER='(63)';
      BIDIRECTIONAL='TRUE';
      INPUT_LOAD='(-0.01,0.01)';
      OUTPUT_LOAD='(1.0,-1.0)';
    'PR5B':
      PIN_NUMBER='(64)';
      BIDIRECTIONAL='TRUE';
      INPUT_LOAD='(-0.01,0.01)';
      OUTPUT_LOAD='(1.0,-1.0)';
    'PR5A':
      PIN_NUMBER='(65)';
      BIDIRECTIONAL='TRUE';
      INPUT_LOAD='(-0.01,0.01)';
      OUTPUT_LOAD='(1.0,-1.0)';
    'PR4D':
      PIN_NUMBER='(66)';
      BIDIRECTIONAL='TRUE';
      INPUT_LOAD='(-0.01,0.01)';
      OUTPUT_LOAD='(1.0,-1.0)';
    'PR4C':
      PIN_NUMBER='(67)';
      BIDIRECTIONAL='TRUE';
      INPUT_LOAD='(-0.01,0.01)';
      OUTPUT_LOAD='(1.0,-1.0)';
    'PR4B':
      PIN_NUMBER='(68)';
      BIDIRECTIONAL='TRUE';
      INPUT_LOAD='(-0.01,0.01)';
      OUTPUT_LOAD='(1.0,-1.0)';
    'PR4A':
      PIN_NUMBER='(69)';
      BIDIRECTIONAL='TRUE';
      INPUT_LOAD='(-0.01,0.01)';
      OUTPUT_LOAD='(1.0,-1.0)';
    'PR3B':
      PIN_NUMBER='(70)';
      BIDIRECTIONAL='TRUE';
      INPUT_LOAD='(-0.01,0.01)';
      OUTPUT_LOAD='(1.0,-1.0)';
    'PR3A':
      PIN_NUMBER='(71)';
      BIDIRECTIONAL='TRUE';
      INPUT_LOAD='(-0.01,0.01)';
      OUTPUT_LOAD='(1.0,-1.0)';
    'PR2B':
      PIN_NUMBER='(74)';
      BIDIRECTIONAL='TRUE';
      INPUT_LOAD='(-0.01,0.01)';
      OUTPUT_LOAD='(1.0,-1.0)';
    'PR2A':
      PIN_NUMBER='(75)';
      BIDIRECTIONAL='TRUE';
      INPUT_LOAD='(-0.01,0.01)';
      OUTPUT_LOAD='(1.0,-1.0)';
    'PT17D':
      PIN_NUMBER='(76)';
      BIDIRECTIONAL='TRUE';
      INPUT_LOAD='(-0.01,0.01)';
      OUTPUT_LOAD='(1.0,-1.0)';
    'PT17C':
      PIN_NUMBER='(77)';
      BIDIRECTIONAL='TRUE';
      INPUT_LOAD='(-0.01,0.01)';
      OUTPUT_LOAD='(1.0,-1.0)';
    'PT16C':
      PIN_NUMBER='(78)';
      BIDIRECTIONAL='TRUE';
      INPUT_LOAD='(-0.01,0.01)';
      OUTPUT_LOAD='(1.0,-1.0)';
    'PT15D':
      PIN_NUMBER='(81)';
      BIDIRECTIONAL='TRUE';
      INPUT_LOAD='(-0.01,0.01)';
      OUTPUT_LOAD='(1.0,-1.0)';
    'PT15C':
      PIN_NUMBER='(82)';
      BIDIRECTIONAL='TRUE';
      INPUT_LOAD='(-0.01,0.01)';
      OUTPUT_LOAD='(1.0,-1.0)';
    'PT15B':
      PIN_NUMBER='(83)';
      BIDIRECTIONAL='TRUE';
      INPUT_LOAD='(-0.01,0.01)';
      OUTPUT_LOAD='(1.0,-1.0)';
    'PT15A':
      PIN_NUMBER='(84)';
      BIDIRECTIONAL='TRUE';
      INPUT_LOAD='(-0.01,0.01)';
      OUTPUT_LOAD='(1.0,-1.0)';
    'PT12D':
      PIN_NUMBER='(85)';
      BIDIRECTIONAL='TRUE';
      INPUT_LOAD='(-0.01,0.01)';
      OUTPUT_LOAD='(1.0,-1.0)';
    'PT12C':
      PIN_NUMBER='(86)';
      BIDIRECTIONAL='TRUE';
      INPUT_LOAD='(-0.01,0.01)';
      OUTPUT_LOAD='(1.0,-1.0)';
    'PT12B':
      PIN_NUMBER='(87)';
      BIDIRECTIONAL='TRUE';
      INPUT_LOAD='(-0.01,0.01)';
      OUTPUT_LOAD='(1.0,-1.0)';
    'PT12A':
      PIN_NUMBER='(88)';
      BIDIRECTIONAL='TRUE';
      INPUT_LOAD='(-0.01,0.01)';
      OUTPUT_LOAD='(1.0,-1.0)';
    'PT11D':
      PIN_NUMBER='(90)';
      BIDIRECTIONAL='TRUE';
      INPUT_LOAD='(-0.01,0.01)';
      OUTPUT_LOAD='(1.0,-1.0)';
    'PT11C':
      PIN_NUMBER='(91)';
      BIDIRECTIONAL='TRUE';
      INPUT_LOAD='(-0.01,0.01)';
      OUTPUT_LOAD='(1.0,-1.0)';
    'PT10D':
      PIN_NUMBER='(94)';
      BIDIRECTIONAL='TRUE';
      INPUT_LOAD='(-0.01,0.01)';
      OUTPUT_LOAD='(1.0,-1.0)';
    'PT10C':
      PIN_NUMBER='(95)';
      BIDIRECTIONAL='TRUE';
      INPUT_LOAD='(-0.01,0.01)';
      OUTPUT_LOAD='(1.0,-1.0)';
    'PT10B':
      PIN_NUMBER='(96)';
      BIDIRECTIONAL='TRUE';
      INPUT_LOAD='(-0.01,0.01)';
      OUTPUT_LOAD='(1.0,-1.0)';
    'PT10A':
      PIN_NUMBER='(97)';
      BIDIRECTIONAL='TRUE';
      INPUT_LOAD='(-0.01,0.01)';
      OUTPUT_LOAD='(1.0,-1.0)';
    'PT9B':
      PIN_NUMBER='(98)';
      BIDIRECTIONAL='TRUE';
      INPUT_LOAD='(-0.01,0.01)';
      OUTPUT_LOAD='(1.0,-1.0)';
    'PT9A':
      PIN_NUMBER='(99)';
      BIDIRECTIONAL='TRUE';
      INPUT_LOAD='(-0.01,0.01)';
      OUTPUT_LOAD='(1.0,-1.0)';
    'GND'<0>:
      PIN_NUMBER='(6)';
      PINUSE='GROUND';
      NO_LOAD_CHECK='Both';
      NO_IO_CHECK='Both';
      NO_ASSERT_CHECK='TRUE';
      NO_DIR_CHECK='TRUE';
      ALLOW_CONNECT='TRUE';
    'GND'<1>:
      PIN_NUMBER='(22)';
      PINUSE='GROUND';
      NO_LOAD_CHECK='Both';
      NO_IO_CHECK='Both';
      NO_ASSERT_CHECK='TRUE';
      NO_DIR_CHECK='TRUE';
      ALLOW_CONNECT='TRUE';
    'GND'<2>:
      PIN_NUMBER='(33)';
      PINUSE='GROUND';
      NO_LOAD_CHECK='Both';
      NO_IO_CHECK='Both';
      NO_ASSERT_CHECK='TRUE';
      NO_DIR_CHECK='TRUE';
      ALLOW_CONNECT='TRUE';
    'GND'<3>:
      PIN_NUMBER='(44)';
      PINUSE='GROUND';
      NO_LOAD_CHECK='Both';
      NO_IO_CHECK='Both';
      NO_ASSERT_CHECK='TRUE';
      NO_DIR_CHECK='TRUE';
      ALLOW_CONNECT='TRUE';
    'GND'<4>:
      PIN_NUMBER='(56)';
      PINUSE='GROUND';
      NO_LOAD_CHECK='Both';
      NO_IO_CHECK='Both';
      NO_ASSERT_CHECK='TRUE';
      NO_DIR_CHECK='TRUE';
      ALLOW_CONNECT='TRUE';
    'GND'<5>:
      PIN_NUMBER='(72)';
      PINUSE='GROUND';
      NO_LOAD_CHECK='Both';
      NO_IO_CHECK='Both';
      NO_ASSERT_CHECK='TRUE';
      NO_DIR_CHECK='TRUE';
      ALLOW_CONNECT='TRUE';
    'GND'<6>:
      PIN_NUMBER='(79)';
      PINUSE='GROUND';
      NO_LOAD_CHECK='Both';
      NO_IO_CHECK='Both';
      NO_ASSERT_CHECK='TRUE';
      NO_DIR_CHECK='TRUE';
      ALLOW_CONNECT='TRUE';
    'GND'<7>:
      PIN_NUMBER='(92)';
      PINUSE='GROUND';
      NO_LOAD_CHECK='Both';
      NO_IO_CHECK='Both';
      NO_ASSERT_CHECK='TRUE';
      NO_DIR_CHECK='TRUE';
      ALLOW_CONNECT='TRUE';
    'NC'<2>:
      PIN_NUMBER='(89)';
      PINUSE='NC';
      NO_LOAD_CHECK='Both';
      NO_IO_CHECK='Both';
      NO_ASSERT_CHECK='TRUE';
      NO_DIR_CHECK='TRUE';
      ALLOW_CONNECT='TRUE';
    'VCCIO3'<0>:
      PIN_NUMBER='(5)';
      PINUSE='POWER';
      NO_LOAD_CHECK='Both';
      NO_IO_CHECK='Both';
      NO_ASSERT_CHECK='TRUE';
      NO_DIR_CHECK='TRUE';
      ALLOW_CONNECT='TRUE';
    'VCCIO3'<2>:
      PIN_NUMBER='(11)';
      PINUSE='POWER';
      NO_LOAD_CHECK='Both';
      NO_IO_CHECK='Both';
      NO_ASSERT_CHECK='TRUE';
      NO_DIR_CHECK='TRUE';
      ALLOW_CONNECT='TRUE';
    'VCCIO3'<1>:
      PIN_NUMBER='(23)';
      PINUSE='POWER';
      NO_LOAD_CHECK='Both';
      NO_IO_CHECK='Both';
      NO_ASSERT_CHECK='TRUE';
      NO_DIR_CHECK='TRUE';
      ALLOW_CONNECT='TRUE';
    'VCCIO2'<0>:
      PIN_NUMBER='(26)';
      PINUSE='POWER';
      NO_LOAD_CHECK='Both';
      NO_IO_CHECK='Both';
      NO_ASSERT_CHECK='TRUE';
      NO_DIR_CHECK='TRUE';
      ALLOW_CONNECT='TRUE';
    'VCCIO2'<1>:
      PIN_NUMBER='(46)';
      PINUSE='POWER';
      NO_LOAD_CHECK='Both';
      NO_IO_CHECK='Both';
      NO_ASSERT_CHECK='TRUE';
      NO_DIR_CHECK='TRUE';
      ALLOW_CONNECT='TRUE';
    'VCC'<0>:
      PIN_NUMBER='(50)';
      PINUSE='POWER';
      NO_LOAD_CHECK='Both';
      NO_IO_CHECK='Both';
      NO_ASSERT_CHECK='TRUE';
      NO_DIR_CHECK='TRUE';
      ALLOW_CONNECT='TRUE';
    'VCCIO1'<0>:
      PIN_NUMBER='(55)';
      PINUSE='POWER';
      NO_LOAD_CHECK='Both';
      NO_IO_CHECK='Both';
      NO_ASSERT_CHECK='TRUE';
      NO_DIR_CHECK='TRUE';
      ALLOW_CONNECT='TRUE';
    'VCCIO1'<1>:
      PIN_NUMBER='(73)';
      PINUSE='POWER';
      NO_LOAD_CHECK='Both';
      NO_IO_CHECK='Both';
      NO_ASSERT_CHECK='TRUE';
      NO_DIR_CHECK='TRUE';
      ALLOW_CONNECT='TRUE';
    'VCCIO0'<0>:
      PIN_NUMBER='(80)';
      PINUSE='POWER';
      NO_LOAD_CHECK='Both';
      NO_IO_CHECK='Both';
      NO_ASSERT_CHECK='TRUE';
      NO_DIR_CHECK='TRUE';
      ALLOW_CONNECT='TRUE';
    'VCCIO0'<1>:
      PIN_NUMBER='(93)';
      PINUSE='POWER';
      NO_LOAD_CHECK='Both';
      NO_IO_CHECK='Both';
      NO_ASSERT_CHECK='TRUE';
      NO_DIR_CHECK='TRUE';
      ALLOW_CONNECT='TRUE';
    'VCC'<1>:
      PIN_NUMBER='(100)';
      PINUSE='POWER';
      NO_LOAD_CHECK='Both';
      NO_IO_CHECK='Both';
      NO_ASSERT_CHECK='TRUE';
      NO_DIR_CHECK='TRUE';
      ALLOW_CONNECT='TRUE';
  end_pin;
  body
    PART_NAME='LCMXO2_A';
    PHYS_DES_PREFIX='U';
  end_body;
end_primitive;

END.
